FILE_TYPE = MACRO_DRAWING;
SET COLOR_WIRE YELLOW;
SET COLOR_PROP ORANGE;
SET COLOR_DOT WHITE;
SET COLOR_ARC YELLOW;
SET COLOR_BODY GREEN;
SET COLOR_NOTE PURPLE;
SET PROP_DISPLAY VALUE;
SET PAGE_NUMBER P380;
FORCEADD GND..1
(-5600 750);
FORCEPROP 3 LASTPIN (-5600 800) SIG_NAME GND\g
J 0
(-5590 810);
DISPLAY 0.659574 (-5590 810);
PAINT MONO (-5590 810);
DISPLAY INVISIBLE (-5590 810);
FORCEPROP 1 LAST PATH I1
J 0
(-5650 825);
DISPLAY 1.021277 (-5650 825);
FORCEPROP 2 LAST CDS_LIB pure_quanta_power
J 0
(-5600 750);
DISPLAY INVISIBLE (-5600 750);
FORCEPROP 1 LAST SIZE 1B
J 0
(-5525 700);
DISPLAY 0.872340 (-5525 700);
PAINT AQUA (-5525 700);
DISPLAY INVISIBLE (-5525 700);
FORCEPROP 1 LAST HDL_POWER GND
J 0
(-5600 900);
DISPLAY 0.872340 (-5600 900);
PAINT GREEN (-5600 900);
DISPLAY INVISIBLE (-5600 900);
FORCEADD Q_CAP..1
(-6300 2500);
FORCEPROP 1 LAST LOCATION PC6015
J 0
(-6250 2625);
DISPLAY 0.617021 (-6250 2625);
PAINT AQUA (-6250 2625);
FORCEPROP 0 LAST $SEC 1
J 0
(-6250 2675);
DISPLAY 0.680851 (-6250 2675);
PAINT MONO (-6250 2675);
DISPLAY INVISIBLE (-6250 2675);
FORCEPROP 0 LAST CDS_SEC 1
J 0
(-6250 2675);
DISPLAY 0.680851 (-6250 2675);
DISPLAY INVISIBLE (-6250 2675);
FORCEPROP 1 LASTPIN (-6300 2600) $PN 1
J 0
(-6290 2580);
DISPLAY 0.787234 (-6290 2580);
PAINT MONO (-6290 2580);
FORCEPROP 1 LASTPIN (-6300 2400) $PN 2
J 0
(-6290 2380);
DISPLAY 0.787234 (-6290 2380);
PAINT MONO (-6290 2380);
FORCEPROP 1 LAST TOLERANCE 20%
J 0
(-6250 2475);
DISPLAY 0.617021 (-6250 2475);
PAINT SKYBLUE (-6250 2475);
FORCEPROP 1 LAST VALUE 22UF
J 0
(-6250 2575);
DISPLAY 0.617021 (-6250 2575);
PAINT SKYBLUE (-6250 2575);
FORCEPROP 1 LAST VOLTAGE 16V
J 0
(-6250 2525);
DISPLAY 0.617021 (-6250 2525);
PAINT SKYBLUE (-6250 2525);
FORCEPROP 1 LAST MATERIAL X6S
J 0
(-6250 2425);
DISPLAY 0.617021 (-6250 2425);
PAINT SKYBLUE (-6250 2425);
FORCEPROP 1 LAST PACK_TYPE C0805
J 0
(-6250 2375);
DISPLAY 0.617021 (-6250 2375);
PAINT SKYBLUE (-6250 2375);
FORCEPROP 2 LAST CDS_LIB pure_quanta
J 0
(-6300 2500);
DISPLAY INVISIBLE (-6300 2500);
FORCEPROP 1 LAST PART_NUMBER CH6223MEA01
J 0
(-6250 2325);
DISPLAY 0.617021 (-6250 2325);
PAINT BLUE (-6250 2325);
DISPLAY INVISIBLE (-6250 2325);
FORCEPROP 1 LAST PATH I10
J 0
(-6250 2650);
DISPLAY 0.978723 (-6250 2650);
PAINT WHITE (-6250 2650);
DISPLAY INVISIBLE (-6250 2650);
FORCEADD Q_RES..1
(-5875 1800);
FORCEPROP 1 LAST LOCATION PR6005
J 0
(-5925 1875);
DISPLAY 0.617021 (-5925 1875);
PAINT AQUA (-5925 1875);
FORCEPROP 0 LAST $SEC 1
J 0
(-5925 1925);
DISPLAY 0.680851 (-5925 1925);
PAINT MONO (-5925 1925);
DISPLAY INVISIBLE (-5925 1925);
FORCEPROP 0 LAST CDS_SEC 1
J 0
(-5925 1925);
DISPLAY 0.680851 (-5925 1925);
DISPLAY INVISIBLE (-5925 1925);
FORCEPROP 1 LASTPIN (-5975 1800) $PN 1
J 0
(-5963 1812);
DISPLAY 0.787234 (-5963 1812);
PAINT MONO (-5963 1812);
FORCEPROP 1 LASTPIN (-5775 1800) $PN 2
J 0
(-5813 1812);
DISPLAY 0.787234 (-5813 1812);
PAINT MONO (-5813 1812);
FORCEPROP 1 LAST WATTAGE 1/16W
J 2
(-5900 1675);
DISPLAY 0.617021 (-5900 1675);
PAINT SKYBLUE (-5900 1675);
FORCEPROP 1 LAST MATERIAL CHIP
J 0
(-6025 1725);
DISPLAY 0.617021 (-6025 1725);
PAINT SKYBLUE (-6025 1725);
FORCEPROP 1 LAST PACK_TYPE 0402LF
J 0
(-5875 1675);
DISPLAY 0.617021 (-5875 1675);
PAINT SKYBLUE (-5875 1675);
FORCEPROP 1 LAST TOLERANCE 1%
J 0
(-5800 1725);
DISPLAY 0.617021 (-5800 1725);
PAINT SKYBLUE (-5800 1725);
FORCEPROP 1 LAST VALUE 60.4K
J 2
(-5975 1800);
DISPLAY 0.617021 (-5975 1800);
PAINT SKYBLUE (-5975 1800);
FORCEPROP 2 LAST CDS_LIB pure_quanta
J 0
(-5875 1800);
DISPLAY INVISIBLE (-5875 1800);
FORCEPROP 1 LAST PART_NUMBER CS36042FB04
J 0
(-6125 1625);
DISPLAY 0.617021 (-6125 1625);
PAINT BLUE (-6125 1625);
DISPLAY INVISIBLE (-6125 1625);
FORCEPROP 1 LAST PATH I11
J 0
(-5925 1950);
DISPLAY 0.978723 (-5925 1950);
PAINT WHITE (-5925 1950);
DISPLAY INVISIBLE (-5925 1950);
FORCEADD Q_CAP..1
(-5700 2500);
FORCEPROP 1 LAST LOCATION PC6011
J 0
(-5650 2625);
DISPLAY 0.617021 (-5650 2625);
PAINT AQUA (-5650 2625);
FORCEPROP 0 LAST $SEC 1
J 0
(-5650 2675);
DISPLAY 0.680851 (-5650 2675);
PAINT MONO (-5650 2675);
DISPLAY INVISIBLE (-5650 2675);
FORCEPROP 0 LAST CDS_SEC 1
J 0
(-5650 2675);
DISPLAY 0.680851 (-5650 2675);
DISPLAY INVISIBLE (-5650 2675);
FORCEPROP 1 LASTPIN (-5700 2600) $PN 1
J 0
(-5690 2580);
DISPLAY 0.787234 (-5690 2580);
PAINT MONO (-5690 2580);
FORCEPROP 1 LASTPIN (-5700 2400) $PN 2
J 0
(-5690 2380);
DISPLAY 0.787234 (-5690 2380);
PAINT MONO (-5690 2380);
FORCEPROP 1 LAST VALUE 1UF
J 0
(-5650 2575);
DISPLAY 0.617021 (-5650 2575);
PAINT SKYBLUE (-5650 2575);
FORCEPROP 1 LAST VOLTAGE 25V
J 0
(-5650 2525);
DISPLAY 0.617021 (-5650 2525);
PAINT SKYBLUE (-5650 2525);
FORCEPROP 1 LAST TOLERANCE 10%
J 0
(-5650 2475);
DISPLAY 0.617021 (-5650 2475);
PAINT SKYBLUE (-5650 2475);
FORCEPROP 1 LAST MATERIAL X6S
J 0
(-5650 2425);
DISPLAY 0.617021 (-5650 2425);
PAINT SKYBLUE (-5650 2425);
FORCEPROP 1 LAST PACK_TYPE C0402
J 0
(-5650 2375);
DISPLAY 0.617021 (-5650 2375);
PAINT SKYBLUE (-5650 2375);
FORCEPROP 2 LAST CDS_LIB pure_quanta
J 0
(-5700 2500);
DISPLAY INVISIBLE (-5700 2500);
FORCEPROP 1 LAST PART_NUMBER CH5104KEB02
J 0
(-5650 2325);
DISPLAY 0.617021 (-5650 2325);
PAINT BLUE (-5650 2325);
DISPLAY INVISIBLE (-5650 2325);
FORCEPROP 1 LAST PATH I12
J 0
(-5650 2650);
DISPLAY 0.978723 (-5650 2650);
PAINT WHITE (-5650 2650);
DISPLAY INVISIBLE (-5650 2650);
FORCEADD UNIVERSAL_POWER..1
(-7700 2850);
FORCEPROP 3 LASTPIN (-7700 2800) SIG_NAME P12V_AUX\g
J 0
(-7690 2810);
DISPLAY 0.659574 (-7690 2810);
PAINT MONO (-7690 2810);
DISPLAY INVISIBLE (-7690 2810);
FORCEPROP 1 LAST HDL_POWER P12V_AUX
J 1
(-7700 2900);
DISPLAY 0.617021 (-7700 2900);
PAINT GREEN (-7700 2900);
FORCEPROP 2 LAST CDS_LIB pure_quanta_power
J 0
(-7700 2850);
DISPLAY INVISIBLE (-7700 2850);
FORCEPROP 1 LAST PATH I13
J 0
(-7650 2875);
DISPLAY 0.872340 (-7650 2875);
PAINT AQUA (-7650 2875);
DISPLAY INVISIBLE (-7650 2875);
FORCEADD GND..1
(-3700 750);
FORCEPROP 3 LASTPIN (-3700 800) SIG_NAME GND\g
J 0
(-3690 810);
DISPLAY 0.659574 (-3690 810);
PAINT MONO (-3690 810);
DISPLAY INVISIBLE (-3690 810);
FORCEPROP 1 LAST PATH I14
J 0
(-3800 825);
DISPLAY 1.021277 (-3800 825);
FORCEPROP 2 LAST CDS_LIB pure_quanta_power
J 0
(-3700 750);
DISPLAY INVISIBLE (-3700 750);
FORCEPROP 1 LAST SIZE 1B
J 0
(-3625 700);
DISPLAY 0.872340 (-3625 700);
PAINT AQUA (-3625 700);
DISPLAY INVISIBLE (-3625 700);
FORCEPROP 1 LAST HDL_POWER GND
J 0
(-3700 900);
DISPLAY 0.872340 (-3700 900);
PAINT GREEN (-3700 900);
DISPLAY INVISIBLE (-3700 900);
FORCEADD GND..1
(-4100 750);
FORCEPROP 3 LASTPIN (-4100 800) SIG_NAME GND\g
J 0
(-4090 810);
DISPLAY 0.659574 (-4090 810);
PAINT MONO (-4090 810);
DISPLAY INVISIBLE (-4090 810);
FORCEPROP 1 LAST PATH I15
J 0
(-4200 825);
DISPLAY 1.021277 (-4200 825);
FORCEPROP 2 LAST CDS_LIB pure_quanta_power
J 0
(-4100 750);
DISPLAY INVISIBLE (-4100 750);
FORCEPROP 1 LAST SIZE 1B
J 0
(-4025 700);
DISPLAY 0.872340 (-4025 700);
PAINT AQUA (-4025 700);
DISPLAY INVISIBLE (-4025 700);
FORCEPROP 1 LAST HDL_POWER GND
J 0
(-4100 900);
DISPLAY 0.872340 (-4100 900);
PAINT GREEN (-4100 900);
DISPLAY INVISIBLE (-4100 900);
FORCEADD MPQ8626GDZ..1
(-4650 1825);
FORCEPROP 1 LAST LOCATION PU6001
J 0
(-4870 2856);
DISPLAY 0.617021 (-4870 2856);
PAINT AQUA (-4870 2856);
FORCEPROP 2 LAST SEC 1
J 0
(-4850 3000);
DISPLAY 0.680851 (-4850 3000);
PAINT MONO (-4850 3000);
DISPLAY INVISIBLE (-4850 3000);
FORCEPROP 2 LASTPIN (-4250 1150) $PN 7
J 0
(-4240 1160);
DISPLAY 0.680851 (-4240 1160);
PAINT MONO (-4240 1160);
FORCEPROP 2 LASTPIN (-4250 2300) $PN 10
J 0
(-4240 2310);
DISPLAY 0.680851 (-4240 2310);
PAINT MONO (-4240 2310);
FORCEPROP 2 LASTPIN (-5050 1200) $PN 4
J 2
(-5060 1210);
DISPLAY 0.680851 (-5060 1210);
PAINT MONO (-5060 1210);
FORCEPROP 2 LASTPIN (-5050 2000) $PN 5
J 2
(-5060 2010);
DISPLAY 0.680851 (-5060 2010);
PAINT MONO (-5060 2010);
FORCEPROP 2 LASTPIN (-4250 1550) $PN 6
J 0
(-4240 1560);
DISPLAY 0.680851 (-4240 1560);
PAINT MONO (-4240 1560);
FORCEPROP 2 LASTPIN (-5050 1800) $PN 12
J 2
(-5060 1810);
DISPLAY 0.680851 (-5060 1810);
PAINT MONO (-5060 1810);
FORCEPROP 2 LASTPIN (-4250 1400) $PN 1
J 0
(-4240 1410);
DISPLAY 0.680851 (-4240 1410);
PAINT MONO (-4240 1410);
FORCEPROP 2 LASTPIN (-4250 1200) $PN 14
J 0
(-4240 1210);
DISPLAY 0.680851 (-4240 1210);
PAINT MONO (-4240 1210);
FORCEPROP 2 LASTPIN (-4250 2500) $PN 9
J 0
(-4240 2510);
DISPLAY 0.680851 (-4240 2510);
PAINT MONO (-4240 2510);
FORCEPROP 2 LASTPIN (-4250 2050) $PN 2
J 0
(-4240 2060);
DISPLAY 0.680851 (-4240 2060);
PAINT MONO (-4240 2060);
FORCEPROP 2 LASTPIN (-4250 2000) $PN 11
J 0
(-4240 2010);
DISPLAY 0.680851 (-4240 2010);
PAINT MONO (-4240 2010);
FORCEPROP 2 LASTPIN (-4250 1300) $PN 8
J 0
(-4240 1310);
DISPLAY 0.680851 (-4240 1310);
PAINT MONO (-4240 1310);
FORCEPROP 2 LASTPIN (-5050 1550) $PN 13
J 2
(-5060 1560);
DISPLAY 0.680851 (-5060 1560);
PAINT MONO (-5060 1560);
FORCEPROP 2 LASTPIN (-5050 2500) $PN 3
J 2
(-5060 2510);
DISPLAY 0.680851 (-5060 2510);
PAINT MONO (-5060 2510);
FORCEPROP 2 LAST PART_TYPE SMLF
J 0
(-4850 2950);
DISPLAY 0.680851 (-4850 2950);
FORCEPROP 1 LAST MATERIAL IC
J 0
(-4870 2582);
DISPLAY 0.617021 (-4870 2582);
PAINT SKYBLUE (-4870 2582);
FORCEPROP 2 LAST VALUE MPQ8626GD-Z
J 0
(-4850 2900);
DISPLAY 0.617021 (-4850 2900);
PAINT SKYBLUE (-4850 2900);
FORCEPROP 1 LAST NEEDS_NO_SIZE TRUE
J 0
(-4650 1825);
DISPLAY 0.723404 (-4650 1825);
PAINT GREEN (-4650 1825);
DISPLAY INVISIBLE (-4650 1825);
FORCEPROP 1 LAST CDS_LMAN_SYM_OUTLINE -250,725,250,-725
J 0
(-4650 1825);
DISPLAY 0.468085 (-4650 1825);
PAINT GREEN (-4650 1825);
DISPLAY INVISIBLE (-4650 1825);
FORCEPROP 2 LAST CDS_LIB pure_quanta
J 0
(-4650 1825);
DISPLAY INVISIBLE (-4650 1825);
FORCEPROP 2 LAST SEC_TYPE 
J 0
(-4850 3000);
DISPLAY 1.021277 (-4850 3000);
DISPLAY INVISIBLE (-4850 3000);
FORCEPROP 1 LAST PART_NUMBER AL008626000
J 0
(-4870 2709);
DISPLAY 0.617021 (-4870 2709);
PAINT BLUE (-4870 2709);
DISPLAY INVISIBLE (-4870 2709);
FORCEPROP 1 LAST PATH I16
J 0
(-4650 1825);
DISPLAY 0.723404 (-4650 1825);
PAINT GREEN (-4650 1825);
DISPLAY INVISIBLE (-4650 1825);
FORCEADD Q_CAP..1
(-3700 1025);
FORCEPROP 1 LAST LOCATION PC6016
J 0
(-3650 1125);
DISPLAY 0.617021 (-3650 1125);
PAINT AQUA (-3650 1125);
FORCEPROP 0 LAST $SEC 1
J 0
(-3650 1175);
DISPLAY 0.680851 (-3650 1175);
PAINT MONO (-3650 1175);
DISPLAY INVISIBLE (-3650 1175);
FORCEPROP 0 LAST CDS_SEC 1
J 0
(-3650 1175);
DISPLAY 0.680851 (-3650 1175);
DISPLAY INVISIBLE (-3650 1175);
FORCEPROP 1 LASTPIN (-3700 1125) $PN 1
J 0
(-3690 1105);
DISPLAY 0.787234 (-3690 1105);
PAINT MONO (-3690 1105);
FORCEPROP 1 LASTPIN (-3700 925) $PN 2
J 0
(-3690 905);
DISPLAY 0.787234 (-3690 905);
PAINT MONO (-3690 905);
FORCEPROP 1 LAST VALUE 3300PF
J 0
(-3650 1075);
DISPLAY 0.617021 (-3650 1075);
PAINT SKYBLUE (-3650 1075);
FORCEPROP 1 LAST PACK_TYPE 0402
J 0
(-3650 825);
DISPLAY 0.617021 (-3650 825);
PAINT SKYBLUE (-3650 825);
FORCEPROP 1 LAST VOLTAGE 50V
J 0
(-3650 1025);
DISPLAY 0.617021 (-3650 1025);
PAINT SKYBLUE (-3650 1025);
FORCEPROP 1 LAST TOLERANCE 10%
J 0
(-3650 975);
DISPLAY 0.617021 (-3650 975);
PAINT SKYBLUE (-3650 975);
FORCEPROP 1 LAST MATERIAL X7R
J 0
(-3650 925);
DISPLAY 0.617021 (-3650 925);
PAINT SKYBLUE (-3650 925);
FORCEPROP 2 LAST CDS_LIB pure_quanta
J 0
(-3700 1025);
DISPLAY INVISIBLE (-3700 1025);
FORCEPROP 1 LAST PART_NUMBER TMP_QCH2336K1B12
J 0
(-3650 875);
DISPLAY 0.617021 (-3650 875);
PAINT BLUE (-3650 875);
DISPLAY INVISIBLE (-3650 875);
FORCEPROP 1 LAST PATH I17
J 0
(-3650 1175);
DISPLAY 0.978723 (-3650 1175);
PAINT WHITE (-3650 1175);
DISPLAY INVISIBLE (-3650 1175);
FORCEADD Q_CAP..1
(-3200 2175);
FORCEPROP 1 LAST LOCATION PC6017
J 0
(-3150 2225);
DISPLAY 0.617021 (-3150 2225);
PAINT AQUA (-3150 2225);
FORCEPROP 0 LAST $SEC 1
J 0
(-3150 2450);
DISPLAY 0.680851 (-3150 2450);
PAINT MONO (-3150 2450);
DISPLAY INVISIBLE (-3150 2450);
FORCEPROP 0 LAST CDS_SEC 1
J 0
(-3150 2450);
DISPLAY 0.680851 (-3150 2450);
DISPLAY INVISIBLE (-3150 2450);
FORCEPROP 1 LASTPIN (-3200 2275) $PN 1
J 0
(-3190 2255);
DISPLAY 0.787234 (-3190 2255);
PAINT MONO (-3190 2255);
FORCEPROP 1 LASTPIN (-3200 2075) $PN 2
J 0
(-3190 2055);
DISPLAY 0.787234 (-3190 2055);
PAINT MONO (-3190 2055);
FORCEPROP 1 LAST VALUE 0.22UF
J 0
(-3150 2200);
DISPLAY 0.489362 (-3150 2200);
PAINT SKYBLUE (-3150 2200);
FORCEPROP 1 LAST VOLTAGE 25V
J 0
(-3150 2175);
DISPLAY 0.489362 (-3150 2175);
PAINT SKYBLUE (-3150 2175);
FORCEPROP 1 LAST TOLERANCE 10%
J 0
(-3150 2150);
DISPLAY 0.489362 (-3150 2150);
PAINT SKYBLUE (-3150 2150);
FORCEPROP 1 LAST MATERIAL X7R
J 0
(-3150 2125);
DISPLAY 0.489362 (-3150 2125);
PAINT SKYBLUE (-3150 2125);
FORCEPROP 1 LAST PACK_TYPE C0402
J 0
(-3150 2075);
DISPLAY 0.489362 (-3150 2075);
PAINT SKYBLUE (-3150 2075);
FORCEPROP 2 LAST CDS_LIB pure_quanta
J 0
(-3200 2175);
DISPLAY INVISIBLE (-3200 2175);
FORCEPROP 1 LAST PART_NUMBER CH4224K1B01
J 0
(-3150 2100);
DISPLAY 0.489362 (-3150 2100);
PAINT SKYBLUE (-3150 2100);
DISPLAY INVISIBLE (-3150 2100);
FORCEPROP 1 LAST PATH I18
J 0
(-3150 2325);
DISPLAY 0.978723 (-3150 2325);
PAINT WHITE (-3150 2325);
DISPLAY INVISIBLE (-3150 2325);
FORCEADD Q_RES..2
(-3550 2800);
FORCEPROP 1 LAST LOCATION R6244
J 0
(-3505 2925);
DISPLAY 0.617021 (-3505 2925);
PAINT AQUA (-3505 2925);
FORCEPROP 0 LAST $SEC 1
J 0
(-3500 2975);
DISPLAY 0.680851 (-3500 2975);
PAINT MONO (-3500 2975);
DISPLAY INVISIBLE (-3500 2975);
FORCEPROP 0 LAST CDS_SEC 1
J 0
(-3500 2975);
DISPLAY 0.680851 (-3500 2975);
DISPLAY INVISIBLE (-3500 2975);
FORCEPROP 1 LASTPIN (-3550 2900) $PN 1
J 0
(-3545 2862);
DISPLAY 0.787234 (-3545 2862);
PAINT MONO (-3545 2862);
FORCEPROP 1 LASTPIN (-3550 2700) $PN 2
J 0
(-3545 2710);
DISPLAY 0.787234 (-3545 2710);
PAINT MONO (-3545 2710);
FORCEPROP 1 LAST MATERIAL CHIP
J 0
(-3510 2725);
DISPLAY 0.617021 (-3510 2725);
PAINT SKYBLUE (-3510 2725);
FORCEPROP 1 LAST PACK_TYPE 0402LF
J 0
(-3510 2625);
DISPLAY 0.617021 (-3510 2625);
PAINT SKYBLUE (-3510 2625);
FORCEPROP 1 LAST VALUE 10K
J 0
(-3505 2875);
DISPLAY 0.617021 (-3505 2875);
PAINT SKYBLUE (-3505 2875);
FORCEPROP 1 LAST TOLERANCE 1%
J 0
(-3505 2825);
DISPLAY 0.617021 (-3505 2825);
PAINT SKYBLUE (-3505 2825);
FORCEPROP 1 LAST WATTAGE 1/16W
J 0
(-3510 2775);
DISPLAY 0.617021 (-3510 2775);
PAINT SKYBLUE (-3510 2775);
FORCEPROP 2 LAST CDS_LIB pure_quanta
J 0
(-3550 2800);
DISPLAY INVISIBLE (-3550 2800);
FORCEPROP 1 LAST PART_NUMBER CS31002FB08
J 0
(-3510 2675);
DISPLAY 0.617021 (-3510 2675);
PAINT BLUE (-3510 2675);
DISPLAY INVISIBLE (-3510 2675);
FORCEPROP 1 LAST PATH I19
J 0
(-3500 2975);
DISPLAY 0.978723 (-3500 2975);
PAINT WHITE (-3500 2975);
DISPLAY INVISIBLE (-3500 2975);
FORCEADD Q_INDUCTOR..1
(-7200 2725);
FORCEPROP 1 LAST LOCATION PL6003
J 0
(-7250 3000);
DISPLAY 0.617021 (-7250 3000);
PAINT AQUA (-7250 3000);
FORCEPROP 0 LAST $SEC 1
J 0
(-7250 3050);
DISPLAY 0.680851 (-7250 3050);
PAINT MONO (-7250 3050);
DISPLAY INVISIBLE (-7250 3050);
FORCEPROP 0 LAST CDS_SEC 1
J 0
(-7250 3050);
DISPLAY 0.680851 (-7250 3050);
DISPLAY INVISIBLE (-7250 3050);
FORCEPROP 0 LASTPIN (-7300 2700) $PN 1
J 2
(-7310 2710);
DISPLAY 0.680851 (-7310 2710);
PAINT MONO (-7310 2710);
FORCEPROP 0 LASTPIN (-7100 2700) $PN 2
J 0
(-7090 2710);
DISPLAY 0.680851 (-7090 2710);
PAINT MONO (-7090 2710);
FORCEPROP 2 LAST PACK_TYPE SMLF
J 0
(-7200 2875);
DISPLAY 0.617021 (-7200 2875);
PAINT SKYBLUE (-7200 2875);
FORCEPROP 1 LAST MATERIAL IND
J 0
(-7325 2875);
DISPLAY 0.617021 (-7325 2875);
PAINT SKYBLUE (-7325 2875);
FORCEPROP 2 LAST VALUE BLM18SN220TN1D/8000MA
J 0
(-7575 2800);
DISPLAY 0.617021 (-7575 2800);
PAINT SKYBLUE (-7575 2800);
FORCEPROP 1 LAST NEEDS_NO_SIZE TRUE
J 0
(-7200 2725);
DISPLAY 0.468085 (-7200 2725);
PAINT GREEN (-7200 2725);
DISPLAY INVISIBLE (-7200 2725);
FORCEPROP 2 LAST CDS_LIB pure_quanta
J 0
(-7200 2725);
DISPLAY INVISIBLE (-7200 2725);
FORCEPROP 1 LAST PART_NUMBER CX220TN1001
J 0
(-7375 2950);
DISPLAY 0.617021 (-7375 2950);
PAINT BLUE (-7375 2950);
DISPLAY INVISIBLE (-7375 2950);
FORCEPROP 1 LAST PATH I2
J 0
(-7125 2780);
DISPLAY 0.723404 (-7125 2780);
PAINT GREEN (-7125 2780);
DISPLAY INVISIBLE (-7125 2780);
FORCEADD GND..1
(-3100 650);
FORCEPROP 3 LASTPIN (-3100 700) SIG_NAME GND\g
J 0
(-3090 710);
DISPLAY 0.659574 (-3090 710);
PAINT MONO (-3090 710);
DISPLAY INVISIBLE (-3090 710);
FORCEPROP 1 LAST PATH I20
J 0
(-3200 725);
DISPLAY 1.021277 (-3200 725);
FORCEPROP 2 LAST CDS_LIB pure_quanta_power
J 0
(-3100 650);
DISPLAY INVISIBLE (-3100 650);
FORCEPROP 1 LAST SIZE 1B
J 0
(-3025 600);
DISPLAY 0.872340 (-3025 600);
PAINT AQUA (-3025 600);
DISPLAY INVISIBLE (-3025 600);
FORCEPROP 1 LAST HDL_POWER GND
J 0
(-3100 800);
DISPLAY 0.872340 (-3100 800);
PAINT GREEN (-3100 800);
DISPLAY INVISIBLE (-3100 800);
FORCEADD Q_RES..2
(-3100 875);
FORCEPROP 1 LAST LOCATION PR6011
J 0
(-3055 1000);
DISPLAY 0.617021 (-3055 1000);
PAINT AQUA (-3055 1000);
FORCEPROP 0 LAST $SEC 1
J 0
(-3050 1050);
DISPLAY 0.680851 (-3050 1050);
PAINT MONO (-3050 1050);
DISPLAY INVISIBLE (-3050 1050);
FORCEPROP 0 LAST CDS_SEC 1
J 0
(-3050 1050);
DISPLAY 0.680851 (-3050 1050);
DISPLAY INVISIBLE (-3050 1050);
FORCEPROP 1 LASTPIN (-3100 975) $PN 1
J 0
(-3095 937);
DISPLAY 0.787234 (-3095 937);
PAINT MONO (-3095 937);
FORCEPROP 1 LASTPIN (-3100 775) $PN 2
J 0
(-3095 785);
DISPLAY 0.787234 (-3095 785);
PAINT MONO (-3095 785);
FORCEPROP 1 LAST MATERIAL CHIP
J 0
(-3060 800);
DISPLAY 0.617021 (-3060 800);
PAINT SKYBLUE (-3060 800);
FORCEPROP 1 LAST WATTAGE 1/16W
J 0
(-3060 850);
DISPLAY 0.617021 (-3060 850);
PAINT SKYBLUE (-3060 850);
FORCEPROP 1 LAST VALUE 10K
J 0
(-3055 950);
DISPLAY 0.617021 (-3055 950);
PAINT SKYBLUE (-3055 950);
FORCEPROP 1 LAST PACK_TYPE 0402LF
J 0
(-3060 700);
DISPLAY 0.617021 (-3060 700);
PAINT SKYBLUE (-3060 700);
FORCEPROP 1 LAST TOLERANCE 1%
J 0
(-3055 900);
DISPLAY 0.617021 (-3055 900);
PAINT SKYBLUE (-3055 900);
FORCEPROP 2 LAST CDS_LIB pure_quanta
J 0
(-3100 875);
DISPLAY INVISIBLE (-3100 875);
FORCEPROP 1 LAST PART_NUMBER CS31002FB08
J 0
(-3060 750);
DISPLAY 0.617021 (-3060 750);
PAINT BLUE (-3060 750);
DISPLAY INVISIBLE (-3060 750);
FORCEPROP 1 LAST PATH I21
J 0
(-3050 1050);
DISPLAY 0.978723 (-3050 1050);
PAINT WHITE (-3050 1050);
DISPLAY INVISIBLE (-3050 1050);
FORCEADD GND..1
(-3400 1250);
FORCEPROP 3 LASTPIN (-3400 1300) SIG_NAME GND\g
J 0
(-3390 1310);
DISPLAY 0.659574 (-3390 1310);
PAINT MONO (-3390 1310);
DISPLAY INVISIBLE (-3390 1310);
FORCEPROP 1 LAST PATH I22
J 0
(-3500 1325);
DISPLAY 1.021277 (-3500 1325);
FORCEPROP 2 LAST CDS_LIB pure_quanta_power
J 0
(-3400 1250);
DISPLAY INVISIBLE (-3400 1250);
FORCEPROP 1 LAST SIZE 1B
J 0
(-3325 1200);
DISPLAY 0.872340 (-3325 1200);
PAINT AQUA (-3325 1200);
DISPLAY INVISIBLE (-3325 1200);
FORCEPROP 1 LAST HDL_POWER GND
J 0
(-3400 1400);
DISPLAY 0.872340 (-3400 1400);
PAINT GREEN (-3400 1400);
DISPLAY INVISIBLE (-3400 1400);
FORCEADD Q_CAP..1
(-2550 1800);
FORCEPROP 1 LAST LOCATION PC6022
J 0
(-2500 1900);
DISPLAY 0.617021 (-2500 1900);
PAINT AQUA (-2500 1900);
FORCEPROP 0 LAST $SEC 1
J 0
(-2500 1950);
DISPLAY 0.680851 (-2500 1950);
PAINT MONO (-2500 1950);
DISPLAY INVISIBLE (-2500 1950);
FORCEPROP 0 LAST CDS_SEC 1
J 0
(-2500 1950);
DISPLAY 0.680851 (-2500 1950);
DISPLAY INVISIBLE (-2500 1950);
FORCEPROP 1 LASTPIN (-2550 1900) $PN 1
J 0
(-2540 1880);
DISPLAY 0.787234 (-2540 1880);
PAINT MONO (-2540 1880);
FORCEPROP 1 LASTPIN (-2550 1700) $PN 2
J 0
(-2540 1680);
DISPLAY 0.787234 (-2540 1680);
PAINT MONO (-2540 1680);
FORCEPROP 1 LAST PACK_TYPE C0402
J 0
(-2500 1600);
DISPLAY 0.617021 (-2500 1600);
PAINT SKYBLUE (-2500 1600);
FORCEPROP 1 LAST MATERIAL X7R
J 0
(-2500 1700);
DISPLAY 0.617021 (-2500 1700);
PAINT SKYBLUE (-2500 1700);
FORCEPROP 1 LAST TOLERANCE 10%
J 0
(-2500 1750);
DISPLAY 0.617021 (-2500 1750);
PAINT SKYBLUE (-2500 1750);
FORCEPROP 1 LAST VOLTAGE 50V
J 0
(-2500 1800);
DISPLAY 0.617021 (-2500 1800);
PAINT SKYBLUE (-2500 1800);
FORCEPROP 1 LAST VALUE 100NF
J 0
(-2500 1850);
DISPLAY 0.617021 (-2500 1850);
PAINT SKYBLUE (-2500 1850);
FORCEPROP 2 LAST CDS_LIB pure_quanta
J 0
(-2550 1800);
DISPLAY INVISIBLE (-2550 1800);
FORCEPROP 1 LAST PART_NUMBER CH4106K1B01
J 0
(-2500 1650);
DISPLAY 0.617021 (-2500 1650);
PAINT BLUE (-2500 1650);
DISPLAY INVISIBLE (-2500 1650);
FORCEPROP 1 LAST PATH I23
J 0
(-2500 1950);
DISPLAY 0.978723 (-2500 1950);
PAINT WHITE (-2500 1950);
DISPLAY INVISIBLE (-2500 1950);
FORCEADD Q_INDUCTOR..1
(-2725 2025);
FORCEPROP 1 LAST LOCATION PL6001
J 0
(-2775 2125);
DISPLAY 0.617021 (-2775 2125);
PAINT AQUA (-2775 2125);
FORCEPROP 0 LAST $SEC 1
J 0
(-2775 2325);
DISPLAY 0.680851 (-2775 2325);
PAINT MONO (-2775 2325);
DISPLAY INVISIBLE (-2775 2325);
FORCEPROP 0 LAST CDS_SEC 1
J 0
(-2775 2325);
DISPLAY 0.680851 (-2775 2325);
DISPLAY INVISIBLE (-2775 2325);
FORCEPROP 0 LASTPIN (-2825 2000) $PN 1
J 2
(-2835 2010);
DISPLAY 0.680851 (-2835 2010);
PAINT MONO (-2835 2010);
FORCEPROP 0 LASTPIN (-2625 2000) $PN 2
J 0
(-2615 2010);
DISPLAY 0.680851 (-2615 2010);
PAINT MONO (-2615 2010);
FORCEPROP 1 LAST MATERIAL IND
J 0
(-2775 2075);
DISPLAY 0.617021 (-2775 2075);
PAINT SKYBLUE (-2775 2075);
FORCEPROP 2 LAST PACK_TYPE SMLF
J 0
(-2775 2220);
DISPLAY 0.617021 (-2775 2220);
PAINT SKYBLUE (-2775 2220);
FORCEPROP 2 LAST VALUE 2.2UH
J 0
(-2775 2275);
DISPLAY 0.617021 (-2775 2275);
PAINT SKYBLUE (-2775 2275);
FORCEPROP 2 LAST CDS_LIB pure_quanta
J 0
(-2725 2025);
DISPLAY INVISIBLE (-2725 2025);
FORCEPROP 1 LAST NEEDS_NO_SIZE TRUE
J 0
(-2725 2025);
DISPLAY 0.468085 (-2725 2025);
PAINT GREEN (-2725 2025);
DISPLAY INVISIBLE (-2725 2025);
FORCEPROP 1 LAST PART_NUMBER CV-2280MZ15
J 0
(-2775 2175);
DISPLAY 0.617021 (-2775 2175);
PAINT BLUE (-2775 2175);
DISPLAY INVISIBLE (-2775 2175);
FORCEPROP 1 LAST PATH I24
J 0
(-2650 2080);
DISPLAY 0.723404 (-2650 2080);
PAINT GREEN (-2650 2080);
DISPLAY INVISIBLE (-2650 2080);
FORCEADD Q_CAP..2
(-2050 800);
FORCEPROP 1 LAST LOCATION PC852
J 1
(-2050 875);
DISPLAY 0.617021 (-2050 875);
PAINT AQUA (-2050 875);
FORCEPROP 0 LAST $SEC 1
J 0
(-2050 925);
DISPLAY 0.680851 (-2050 925);
PAINT MONO (-2050 925);
DISPLAY INVISIBLE (-2050 925);
FORCEPROP 0 LAST CDS_SEC 1
J 0
(-2050 925);
DISPLAY 0.680851 (-2050 925);
DISPLAY INVISIBLE (-2050 925);
FORCEPROP 1 LASTPIN (-2150 800) $PN 1
J 0
(-2160 815);
DISPLAY 0.787234 (-2160 815);
PAINT MONO (-2160 815);
FORCEPROP 1 LASTPIN (-1950 800) $PN 2
J 0
(-1965 815);
DISPLAY 0.787234 (-1965 815);
PAINT MONO (-1965 815);
FORCEPROP 1 LAST MATERIAL X7R
J 0
(-2100 550);
DISPLAY 0.617021 (-2100 550);
PAINT SKYBLUE (-2100 550);
FORCEPROP 1 LAST VOLTAGE 50V
J 0
(-2200 625);
DISPLAY 0.617021 (-2200 625);
PAINT SKYBLUE (-2200 625);
FORCEPROP 1 LAST PACK_TYPE 0402
J 1
(-2025 475);
DISPLAY 0.617021 (-2025 475);
PAINT SKYBLUE (-2025 475);
FORCEPROP 1 LAST VALUE 330PF
J 2
(-1900 700);
DISPLAY 0.617021 (-1900 700);
PAINT SKYBLUE (-1900 700);
FORCEPROP 1 LAST TOLERANCE 10%
J 2
(-1925 625);
DISPLAY 0.617021 (-1925 625);
PAINT SKYBLUE (-1925 625);
FORCEPROP 2 LAST CDS_LIB pure_quanta
J 0
(-2050 800);
DISPLAY INVISIBLE (-2050 800);
FORCEPROP 1 LAST PART_NUMBER CH1336K1B02
J 1
(-2025 425);
DISPLAY 0.617021 (-2025 425);
PAINT BLUE (-2025 425);
DISPLAY INVISIBLE (-2025 425);
FORCEPROP 1 LAST PATH I26
J 0
(-2050 1000);
DISPLAY 0.978723 (-2050 1000);
PAINT WHITE (-2050 1000);
DISPLAY INVISIBLE (-2050 1000);
FORCEADD Q_RES..1
(-2050 1225);
FORCEPROP 1 LAST LOCATION PR6008
J 0
(-2075 1300);
DISPLAY 0.617021 (-2075 1300);
PAINT AQUA (-2075 1300);
FORCEPROP 0 LAST $SEC 1
J 0
(-2075 1350);
DISPLAY 0.680851 (-2075 1350);
PAINT MONO (-2075 1350);
DISPLAY INVISIBLE (-2075 1350);
FORCEPROP 0 LAST CDS_SEC 1
J 0
(-2075 1350);
DISPLAY 0.680851 (-2075 1350);
DISPLAY INVISIBLE (-2075 1350);
FORCEPROP 1 LASTPIN (-2150 1225) $PN 1
J 0
(-2138 1237);
DISPLAY 0.787234 (-2138 1237);
PAINT MONO (-2138 1237);
FORCEPROP 1 LASTPIN (-1950 1225) $PN 2
J 0
(-1988 1237);
DISPLAY 0.787234 (-1988 1237);
PAINT MONO (-1988 1237);
FORCEPROP 1 LAST WATTAGE 1/16W
J 2
(-2075 1025);
DISPLAY 0.617021 (-2075 1025);
PAINT SKYBLUE (-2075 1025);
FORCEPROP 1 LAST TOLERANCE 1%
J 0
(-2000 1100);
DISPLAY 0.617021 (-2000 1100);
PAINT SKYBLUE (-2000 1100);
FORCEPROP 1 LAST VALUE 10K
J 2
(-2025 1100);
DISPLAY 0.617021 (-2025 1100);
PAINT SKYBLUE (-2025 1100);
FORCEPROP 1 LAST PACK_TYPE 0402LF
J 0
(-2050 1025);
DISPLAY 0.617021 (-2050 1025);
PAINT SKYBLUE (-2050 1025);
FORCEPROP 1 LAST MATERIAL CHIP
J 0
(-2050 1075);
DISPLAY 0.978723 (-2050 1075);
PAINT SKYBLUE (-2050 1075);
DISPLAY INVISIBLE (-2050 1075);
FORCEPROP 2 LAST CDS_LIB pure_quanta
J 0
(-2050 1225);
DISPLAY INVISIBLE (-2050 1225);
FORCEPROP 1 LAST PART_NUMBER CS31002FB08
J 0
(-2300 950);
DISPLAY 0.617021 (-2300 950);
PAINT BLUE (-2300 950);
DISPLAY INVISIBLE (-2300 950);
FORCEPROP 1 LAST PATH I27
J 0
(-2100 1375);
DISPLAY 0.978723 (-2100 1375);
PAINT WHITE (-2100 1375);
DISPLAY INVISIBLE (-2100 1375);
FORCEADD Q_CAP..1
(-2150 1800);
FORCEPROP 1 LAST LOCATION PC6024
J 0
(-2100 1900);
DISPLAY 0.617021 (-2100 1900);
PAINT AQUA (-2100 1900);
FORCEPROP 0 LAST $SEC 1
J 0
(-2100 1950);
DISPLAY 0.680851 (-2100 1950);
PAINT MONO (-2100 1950);
DISPLAY INVISIBLE (-2100 1950);
FORCEPROP 0 LAST CDS_SEC 1
J 0
(-2100 1950);
DISPLAY 0.680851 (-2100 1950);
DISPLAY INVISIBLE (-2100 1950);
FORCEPROP 1 LASTPIN (-2150 1900) $PN 1
J 0
(-2140 1880);
DISPLAY 0.787234 (-2140 1880);
PAINT MONO (-2140 1880);
FORCEPROP 1 LASTPIN (-2150 1700) $PN 2
J 0
(-2140 1680);
DISPLAY 0.787234 (-2140 1680);
PAINT MONO (-2140 1680);
FORCEPROP 1 LAST MATERIAL X6S
J 0
(-2100 1700);
DISPLAY 0.617021 (-2100 1700);
PAINT SKYBLUE (-2100 1700);
FORCEPROP 1 LAST TOLERANCE 20%
J 0
(-2100 1750);
DISPLAY 0.617021 (-2100 1750);
PAINT SKYBLUE (-2100 1750);
FORCEPROP 1 LAST VOLTAGE 4V
J 0
(-2100 1800);
DISPLAY 0.617021 (-2100 1800);
PAINT SKYBLUE (-2100 1800);
FORCEPROP 1 LAST VALUE 22UF
J 0
(-2100 1850);
DISPLAY 0.617021 (-2100 1850);
PAINT SKYBLUE (-2100 1850);
FORCEPROP 1 LAST PACK_TYPE C0805
J 0
(-2100 1600);
DISPLAY 0.617021 (-2100 1600);
PAINT SKYBLUE (-2100 1600);
FORCEPROP 2 LAST CDS_LIB pure_quanta
J 0
(-2150 1800);
DISPLAY INVISIBLE (-2150 1800);
FORCEPROP 1 LAST PART_NUMBER CH622KMEA03
J 0
(-2100 1650);
DISPLAY 0.617021 (-2100 1650);
PAINT BLUE (-2100 1650);
DISPLAY INVISIBLE (-2100 1650);
FORCEPROP 1 LAST PATH I28
J 0
(-2100 1950);
DISPLAY 0.978723 (-2100 1950);
PAINT WHITE (-2100 1950);
DISPLAY INVISIBLE (-2100 1950);
FORCEADD Q_CAP..1
(-1725 1800);
FORCEPROP 1 LAST LOCATION PC6025
J 0
(-1675 1900);
DISPLAY 0.617021 (-1675 1900);
PAINT AQUA (-1675 1900);
FORCEPROP 0 LAST $SEC 1
J 0
(-1675 1950);
DISPLAY 0.680851 (-1675 1950);
PAINT MONO (-1675 1950);
DISPLAY INVISIBLE (-1675 1950);
FORCEPROP 0 LAST CDS_SEC 1
J 0
(-1675 1950);
DISPLAY 0.680851 (-1675 1950);
DISPLAY INVISIBLE (-1675 1950);
FORCEPROP 1 LASTPIN (-1725 1900) $PN 1
J 0
(-1715 1880);
DISPLAY 0.787234 (-1715 1880);
PAINT MONO (-1715 1880);
FORCEPROP 1 LASTPIN (-1725 1700) $PN 2
J 0
(-1715 1680);
DISPLAY 0.787234 (-1715 1680);
PAINT MONO (-1715 1680);
FORCEPROP 1 LAST VALUE 22UF
J 0
(-1675 1850);
DISPLAY 0.617021 (-1675 1850);
PAINT SKYBLUE (-1675 1850);
FORCEPROP 1 LAST TOLERANCE 20%
J 0
(-1675 1750);
DISPLAY 0.617021 (-1675 1750);
PAINT SKYBLUE (-1675 1750);
FORCEPROP 1 LAST MATERIAL X6S
J 0
(-1675 1700);
DISPLAY 0.617021 (-1675 1700);
PAINT SKYBLUE (-1675 1700);
FORCEPROP 1 LAST PACK_TYPE C0805
J 0
(-1675 1600);
DISPLAY 0.617021 (-1675 1600);
PAINT SKYBLUE (-1675 1600);
FORCEPROP 1 LAST VOLTAGE 4V
J 0
(-1675 1800);
DISPLAY 0.617021 (-1675 1800);
PAINT SKYBLUE (-1675 1800);
FORCEPROP 2 LAST CDS_LIB pure_quanta
J 0
(-1725 1800);
DISPLAY INVISIBLE (-1725 1800);
FORCEPROP 1 LAST PART_NUMBER CH622KMEA03
J 0
(-1675 1650);
DISPLAY 0.617021 (-1675 1650);
PAINT BLUE (-1675 1650);
DISPLAY INVISIBLE (-1675 1650);
FORCEPROP 1 LAST PATH I29
J 0
(-1675 1950);
DISPLAY 0.978723 (-1675 1950);
PAINT WHITE (-1675 1950);
DISPLAY INVISIBLE (-1675 1950);
FORCEADD Q_CAP..1
(-6900 2500);
FORCEPROP 1 LAST LOCATION PC6013
J 0
(-6850 2625);
DISPLAY 0.617021 (-6850 2625);
PAINT AQUA (-6850 2625);
FORCEPROP 0 LAST $SEC 1
J 0
(-6850 2675);
DISPLAY 0.680851 (-6850 2675);
PAINT MONO (-6850 2675);
DISPLAY INVISIBLE (-6850 2675);
FORCEPROP 0 LAST CDS_SEC 1
J 0
(-6850 2675);
DISPLAY 0.680851 (-6850 2675);
DISPLAY INVISIBLE (-6850 2675);
FORCEPROP 1 LASTPIN (-6900 2600) $PN 1
J 0
(-6890 2580);
DISPLAY 0.787234 (-6890 2580);
PAINT MONO (-6890 2580);
FORCEPROP 1 LASTPIN (-6900 2400) $PN 2
J 0
(-6890 2380);
DISPLAY 0.787234 (-6890 2380);
PAINT MONO (-6890 2380);
FORCEPROP 1 LAST MATERIAL X6S
J 0
(-6850 2425);
DISPLAY 0.617021 (-6850 2425);
PAINT SKYBLUE (-6850 2425);
FORCEPROP 1 LAST TOLERANCE 20%
J 0
(-6850 2475);
DISPLAY 0.617021 (-6850 2475);
PAINT SKYBLUE (-6850 2475);
FORCEPROP 1 LAST VOLTAGE 16V
J 0
(-6850 2525);
DISPLAY 0.617021 (-6850 2525);
PAINT SKYBLUE (-6850 2525);
FORCEPROP 1 LAST VALUE 22UF
J 0
(-6850 2575);
DISPLAY 0.617021 (-6850 2575);
PAINT SKYBLUE (-6850 2575);
FORCEPROP 1 LAST PACK_TYPE C0805
J 0
(-6850 2375);
DISPLAY 0.617021 (-6850 2375);
PAINT SKYBLUE (-6850 2375);
FORCEPROP 2 LAST CDS_LIB pure_quanta
J 0
(-6900 2500);
DISPLAY INVISIBLE (-6900 2500);
FORCEPROP 1 LAST PART_NUMBER CH6223MEA01
J 0
(-6850 2325);
DISPLAY 0.617021 (-6850 2325);
PAINT BLUE (-6850 2325);
DISPLAY INVISIBLE (-6850 2325);
FORCEPROP 1 LAST PATH I3
J 0
(-6850 2650);
DISPLAY 0.978723 (-6850 2650);
PAINT WHITE (-6850 2650);
DISPLAY INVISIBLE (-6850 2650);
FORCEADD GND..1
(-1500 1450);
FORCEPROP 3 LASTPIN (-1500 1500) SIG_NAME GND\g
J 0
(-1490 1510);
DISPLAY 0.659574 (-1490 1510);
PAINT MONO (-1490 1510);
DISPLAY INVISIBLE (-1490 1510);
FORCEPROP 1 LAST PATH I30
J 0
(-1600 1525);
DISPLAY 1.021277 (-1600 1525);
FORCEPROP 2 LAST CDS_LIB pure_quanta_power
J 0
(-1500 1450);
DISPLAY INVISIBLE (-1500 1450);
FORCEPROP 1 LAST SIZE 1B
J 0
(-1425 1400);
DISPLAY 0.872340 (-1425 1400);
PAINT AQUA (-1425 1400);
DISPLAY INVISIBLE (-1425 1400);
FORCEPROP 1 LAST HDL_POWER GND
J 0
(-1500 1600);
DISPLAY 0.872340 (-1500 1600);
PAINT GREEN (-1500 1600);
DISPLAY INVISIBLE (-1500 1600);
FORCEADD UNIVERSAL_POWER..1
(-3550 3100);
FORCEPROP 3 LASTPIN (-3550 3050) SIG_NAME P3V3_AUX\g
J 0
(-3540 3060);
DISPLAY 0.659574 (-3540 3060);
PAINT MONO (-3540 3060);
DISPLAY INVISIBLE (-3540 3060);
FORCEPROP 1 LAST HDL_POWER P3V3_AUX
J 1
(-3550 3150);
DISPLAY 0.617021 (-3550 3150);
PAINT GREEN (-3550 3150);
FORCEPROP 2 LAST CDS_LIB pure_quanta_power
J 0
(-3550 3100);
DISPLAY INVISIBLE (-3550 3100);
FORCEPROP 1 LAST PATH I31
J 0
(-3500 3125);
DISPLAY 0.872340 (-3500 3125);
PAINT AQUA (-3500 3125);
DISPLAY INVISIBLE (-3500 3125);
FORCEADD Q_CAP..1
(-1300 1800);
FORCEPROP 1 LAST LOCATION PC6026
J 0
(-1250 1900);
DISPLAY 0.617021 (-1250 1900);
PAINT AQUA (-1250 1900);
FORCEPROP 0 LAST $SEC 1
J 0
(-1250 1950);
DISPLAY 0.680851 (-1250 1950);
PAINT MONO (-1250 1950);
DISPLAY INVISIBLE (-1250 1950);
FORCEPROP 0 LAST CDS_SEC 1
J 0
(-1250 1950);
DISPLAY 0.680851 (-1250 1950);
DISPLAY INVISIBLE (-1250 1950);
FORCEPROP 1 LASTPIN (-1300 1900) $PN 1
J 0
(-1290 1880);
DISPLAY 0.787234 (-1290 1880);
PAINT MONO (-1290 1880);
FORCEPROP 1 LASTPIN (-1300 1700) $PN 2
J 0
(-1290 1680);
DISPLAY 0.787234 (-1290 1680);
PAINT MONO (-1290 1680);
FORCEPROP 1 LAST VOLTAGE 4V
J 0
(-1250 1800);
DISPLAY 0.617021 (-1250 1800);
PAINT SKYBLUE (-1250 1800);
FORCEPROP 1 LAST PACK_TYPE C0805
J 0
(-1250 1600);
DISPLAY 0.617021 (-1250 1600);
PAINT SKYBLUE (-1250 1600);
FORCEPROP 1 LAST MATERIAL X6S
J 0
(-1250 1700);
DISPLAY 0.617021 (-1250 1700);
PAINT SKYBLUE (-1250 1700);
FORCEPROP 1 LAST TOLERANCE 20%
J 0
(-1250 1750);
DISPLAY 0.617021 (-1250 1750);
PAINT SKYBLUE (-1250 1750);
FORCEPROP 1 LAST VALUE 22UF
J 0
(-1250 1850);
DISPLAY 0.617021 (-1250 1850);
PAINT SKYBLUE (-1250 1850);
FORCEPROP 2 LAST CDS_LIB pure_quanta
J 0
(-1300 1800);
DISPLAY INVISIBLE (-1300 1800);
FORCEPROP 1 LAST PART_NUMBER CH622KMEA03
J 0
(-1250 1650);
DISPLAY 0.617021 (-1250 1650);
PAINT BLUE (-1250 1650);
DISPLAY INVISIBLE (-1250 1650);
FORCEPROP 1 LAST PATH I32
J 0
(-1250 1950);
DISPLAY 0.978723 (-1250 1950);
PAINT WHITE (-1250 1950);
DISPLAY INVISIBLE (-1250 1950);
FORCEADD Q_CAP..1
(-800 1800);
FORCEPROP 1 LAST LOCATION PC6018
J 0
(-750 1900);
DISPLAY 0.617021 (-750 1900);
PAINT AQUA (-750 1900);
FORCEPROP 0 LAST $SEC 1
J 0
(-750 1950);
DISPLAY 0.680851 (-750 1950);
PAINT MONO (-750 1950);
DISPLAY INVISIBLE (-750 1950);
FORCEPROP 0 LAST CDS_SEC 1
J 0
(-750 1950);
DISPLAY 0.680851 (-750 1950);
DISPLAY INVISIBLE (-750 1950);
FORCEPROP 1 LASTPIN (-800 1900) $PN 1
J 0
(-790 1880);
DISPLAY 0.787234 (-790 1880);
PAINT MONO (-790 1880);
FORCEPROP 1 LASTPIN (-800 1700) $PN 2
J 0
(-790 1680);
DISPLAY 0.787234 (-790 1680);
PAINT MONO (-790 1680);
FORCEPROP 1 LAST VOLTAGE 4V
J 0
(-750 1800);
DISPLAY 0.617021 (-750 1800);
PAINT SKYBLUE (-750 1800);
FORCEPROP 1 LAST TOLERANCE 20%
J 0
(-750 1750);
DISPLAY 0.617021 (-750 1750);
PAINT SKYBLUE (-750 1750);
FORCEPROP 1 LAST PACK_TYPE C0805
J 0
(-750 1600);
DISPLAY 0.617021 (-750 1600);
PAINT SKYBLUE (-750 1600);
FORCEPROP 1 LAST VALUE 22UF
J 0
(-750 1850);
DISPLAY 0.617021 (-750 1850);
PAINT SKYBLUE (-750 1850);
FORCEPROP 1 LAST MATERIAL X6S
J 0
(-750 1700);
DISPLAY 0.617021 (-750 1700);
PAINT SKYBLUE (-750 1700);
FORCEPROP 2 LAST CDS_LIB pure_quanta
J 0
(-800 1800);
DISPLAY INVISIBLE (-800 1800);
FORCEPROP 1 LAST PART_NUMBER CH622KMEA03
J 0
(-750 1650);
DISPLAY 0.617021 (-750 1650);
PAINT BLUE (-750 1650);
DISPLAY INVISIBLE (-750 1650);
FORCEPROP 1 LAST PATH I33
J 0
(-750 1950);
DISPLAY 0.978723 (-750 1950);
PAINT WHITE (-750 1950);
DISPLAY INVISIBLE (-750 1950);
FORCEADD UNIVERSAL_POWER..1
(-1300 2150);
FORCEPROP 3 LASTPIN (-1300 2100) SIG_NAME P1V2_AUX\g
J 0
(-1290 2110);
DISPLAY 0.659574 (-1290 2110);
PAINT MONO (-1290 2110);
DISPLAY INVISIBLE (-1290 2110);
FORCEPROP 1 LAST HDL_POWER P1V2_AUX
J 1
(-1300 2200);
DISPLAY 0.617021 (-1300 2200);
PAINT GREEN (-1300 2200);
FORCEPROP 2 LAST CDS_LIB pure_quanta_power
J 0
(-1300 2150);
DISPLAY INVISIBLE (-1300 2150);
FORCEPROP 1 LAST PATH I34
J 0
(-1250 2175);
DISPLAY 0.872340 (-1250 2175);
PAINT AQUA (-1250 2175);
DISPLAY INVISIBLE (-1250 2175);
FORCEADD Q_CAP..1
(-7700 2500);
FORCEPROP 1 LAST LOCATION PC6023
J 0
(-7650 2600);
DISPLAY 0.617021 (-7650 2600);
PAINT AQUA (-7650 2600);
FORCEPROP 0 LAST $SEC 1
J 0
(-7650 2650);
DISPLAY 0.680851 (-7650 2650);
PAINT MONO (-7650 2650);
DISPLAY INVISIBLE (-7650 2650);
FORCEPROP 0 LAST CDS_SEC 1
J 0
(-7650 2650);
DISPLAY 0.680851 (-7650 2650);
DISPLAY INVISIBLE (-7650 2650);
FORCEPROP 1 LASTPIN (-7700 2600) $PN 1
J 0
(-7690 2580);
DISPLAY 0.787234 (-7690 2580);
PAINT MONO (-7690 2580);
FORCEPROP 1 LASTPIN (-7700 2400) $PN 2
J 0
(-7690 2380);
DISPLAY 0.787234 (-7690 2380);
PAINT MONO (-7690 2380);
FORCEPROP 1 LAST VALUE 100NF
J 0
(-7650 2550);
DISPLAY 0.617021 (-7650 2550);
PAINT SKYBLUE (-7650 2550);
FORCEPROP 1 LAST VOLTAGE 50V
J 0
(-7650 2500);
DISPLAY 0.617021 (-7650 2500);
PAINT SKYBLUE (-7650 2500);
FORCEPROP 1 LAST MATERIAL X7R
J 0
(-7650 2400);
DISPLAY 0.617021 (-7650 2400);
PAINT SKYBLUE (-7650 2400);
FORCEPROP 1 LAST TOLERANCE 10%
J 0
(-7650 2450);
DISPLAY 0.617021 (-7650 2450);
PAINT SKYBLUE (-7650 2450);
FORCEPROP 1 LAST PACK_TYPE C0402
J 0
(-7650 2300);
DISPLAY 0.617021 (-7650 2300);
PAINT SKYBLUE (-7650 2300);
FORCEPROP 2 LAST CDS_LIB pure_quanta
J 0
(-7700 2500);
DISPLAY INVISIBLE (-7700 2500);
FORCEPROP 1 LAST PART_NUMBER CH4106K1B01
J 0
(-7650 2350);
DISPLAY 0.617021 (-7650 2350);
PAINT BLUE (-7650 2350);
DISPLAY INVISIBLE (-7650 2350);
FORCEPROP 1 LAST PATH I35
J 0
(-7650 2650);
DISPLAY 0.978723 (-7650 2650);
PAINT WHITE (-7650 2650);
DISPLAY INVISIBLE (-7650 2650);
FORCEADD GND..1
(-7700 2250);
FORCEPROP 3 LASTPIN (-7700 2300) SIG_NAME GND\g
J 0
(-7690 2310);
DISPLAY 0.659574 (-7690 2310);
PAINT MONO (-7690 2310);
DISPLAY INVISIBLE (-7690 2310);
FORCEPROP 1 LAST PATH I36
J 0
(-7825 2325);
DISPLAY 1.021277 (-7825 2325);
FORCEPROP 2 LAST CDS_LIB pure_quanta_power
J 0
(-7700 2250);
DISPLAY INVISIBLE (-7700 2250);
FORCEPROP 1 LAST SIZE 1B
J 0
(-7625 2200);
DISPLAY 0.872340 (-7625 2200);
PAINT AQUA (-7625 2200);
DISPLAY INVISIBLE (-7625 2200);
FORCEPROP 1 LAST HDL_POWER GND
J 0
(-7700 2400);
DISPLAY 0.872340 (-7700 2400);
PAINT GREEN (-7700 2400);
DISPLAY INVISIBLE (-7700 2400);
FORCEADD UNIVERSAL_POWER..1
(-6775 1700);
FORCEPROP 3 LASTPIN (-6775 1650) SIG_NAME P3V3_AUX\g
J 0
(-6765 1660);
DISPLAY 0.659574 (-6765 1660);
PAINT MONO (-6765 1660);
DISPLAY INVISIBLE (-6765 1660);
FORCEPROP 1 LAST HDL_POWER P3V3_AUX
J 1
(-6775 1750);
DISPLAY 0.617021 (-6775 1750);
PAINT GREEN (-6775 1750);
FORCEPROP 2 LAST CDS_LIB pure_quanta_power
J 0
(-6775 1700);
DISPLAY INVISIBLE (-6775 1700);
FORCEPROP 1 LAST PATH I37
J 0
(-6725 1725);
DISPLAY 0.872340 (-6725 1725);
PAINT AQUA (-6725 1725);
DISPLAY INVISIBLE (-6725 1725);
FORCEADD Q_RES..2
R 3
(-6400 1550);
FORCEPROP 1 LAST LOCATION R6245
R 1
J 2
(-6525 1505);
DISPLAY 0.617021 (-6525 1505);
PAINT AQUA (-6525 1505);
FORCEPROP 0 LAST $SEC 1
R 1
J 0
(-6300 1600);
DISPLAY 0.680851 (-6300 1600);
PAINT MONO (-6300 1600);
DISPLAY INVISIBLE (-6300 1600);
FORCEPROP 0 LAST CDS_SEC 1
R 1
J 0
(-6300 1600);
DISPLAY 0.680851 (-6300 1600);
DISPLAY INVISIBLE (-6300 1600);
FORCEPROP 1 LASTPIN (-6500 1550) $PN 1
R 1
J 2
(-6462 1545);
DISPLAY 0.787234 (-6462 1545);
PAINT MONO (-6462 1545);
FORCEPROP 1 LASTPIN (-6300 1550) $PN 2
R 1
J 2
(-6310 1545);
DISPLAY 0.787234 (-6310 1545);
PAINT MONO (-6310 1545);
FORCEPROP 1 LAST WATTAGE 1/16W
R 1
J 2
(-6375 1510);
DISPLAY 0.617021 (-6375 1510);
PAINT SKYBLUE (-6375 1510);
FORCEPROP 1 LAST TOLERANCE 5%
R 1
J 2
(-6425 1505);
DISPLAY 0.617021 (-6425 1505);
PAINT SKYBLUE (-6425 1505);
FORCEPROP 1 LAST PACK_TYPE 0402LF
R 1
J 2
(-6225 1510);
DISPLAY 0.617021 (-6225 1510);
PAINT SKYBLUE (-6225 1510);
FORCEPROP 1 LAST VALUE 0
R 1
J 2
(-6475 1505);
DISPLAY 0.617021 (-6475 1505);
PAINT SKYBLUE (-6475 1505);
FORCEPROP 1 LAST MATERIAL CHIP
R 1
J 2
(-6325 1510);
DISPLAY 0.617021 (-6325 1510);
PAINT SKYBLUE (-6325 1510);
FORCEPROP 2 LAST CDS_LIB pure_quanta
R 1
J 2
(-6400 1550);
DISPLAY INVISIBLE (-6400 1550);
FORCEPROP 1 LAST PART_NUMBER CS00002JB13
R 1
J 2
(-6275 1510);
DISPLAY 0.617021 (-6275 1510);
PAINT BLUE (-6275 1510);
DISPLAY INVISIBLE (-6275 1510);
FORCEPROP 1 LAST PATH I38
R 1
J 2
(-6575 1500);
DISPLAY 0.978723 (-6575 1500);
PAINT WHITE (-6575 1500);
DISPLAY INVISIBLE (-6575 1500);
FORCEADD OFFPAGE..4
R 2
(-8125 2000);
FORCEPROP 2 LAST $XR3 255 
J 0
(-8377 1964);
DISPLAY 0.638298 (-8377 1964);
PAINT MONO (-8377 1964);
FORCEPROP 2 LAST $XR2 148 
J 0
(-8587 2000);
DISPLAY 0.638298 (-8587 2000);
PAINT MONO (-8587 2000);
FORCEPROP 2 LAST $XR1 81 
J 0
(-8467 2000);
DISPLAY 0.638298 (-8467 2000);
PAINT MONO (-8467 2000);
FORCEPROP 2 LAST $XR0 270 
J 0
(-8377 2000);
DISPLAY 0.638298 (-8377 2000);
PAINT MONO (-8377 2000);
FORCEPROP 2 LAST CDS_LIB standard
J 0
(-8125 2000);
DISPLAY INVISIBLE (-8125 2000);
FORCEPROP 1 LAST OFFPAGE TRUE
J 2
(-8450 1875);
DISPLAY 0.872340 (-8450 1875);
PAINT GREEN (-8450 1875);
DISPLAY INVISIBLE (-8450 1875);
FORCEPROP 1 LAST COMMENT_BODY TRUE
J 2
(-8100 1900);
DISPLAY 0.872340 (-8100 1900);
PAINT GREEN (-8100 1900);
DISPLAY INVISIBLE (-8100 1900);
FORCEPROP 2 LAST PATH I39
J 0
(-8075 2075);
DISPLAY 0.680851 (-8075 2075);
DISPLAY INVISIBLE (-8075 2075);
FORCEADD GND..1
(-6300 1650);
FORCEPROP 3 LASTPIN (-6300 1700) SIG_NAME GND\g
J 0
(-6290 1710);
DISPLAY 0.659574 (-6290 1710);
PAINT MONO (-6290 1710);
DISPLAY INVISIBLE (-6290 1710);
FORCEPROP 1 LAST PATH I4
J 0
(-6350 1725);
DISPLAY 1.021277 (-6350 1725);
FORCEPROP 2 LAST CDS_LIB pure_quanta_power
J 0
(-6300 1650);
DISPLAY INVISIBLE (-6300 1650);
FORCEPROP 1 LAST SIZE 1B
J 0
(-6225 1600);
DISPLAY 0.872340 (-6225 1600);
PAINT AQUA (-6225 1600);
DISPLAY INVISIBLE (-6225 1600);
FORCEPROP 1 LAST HDL_POWER GND
J 0
(-6300 1800);
DISPLAY 0.872340 (-6300 1800);
PAINT GREEN (-6300 1800);
DISPLAY INVISIBLE (-6300 1800);
FORCEADD Q_RES..1
(-6475 2000);
FORCEPROP 1 LAST LOCATION R6240
J 0
(-6725 2000);
DISPLAY 0.872340 (-6725 2000);
FORCEPROP 0 LAST $SEC 1
J 0
(-6575 2125);
DISPLAY 0.680851 (-6575 2125);
PAINT MONO (-6575 2125);
DISPLAY INVISIBLE (-6575 2125);
FORCEPROP 0 LAST CDS_SEC 1
J 0
(-6575 2125);
DISPLAY 0.680851 (-6575 2125);
DISPLAY INVISIBLE (-6575 2125);
FORCEPROP 1 LASTPIN (-6575 2000) $PN 1
J 0
(-6563 2012);
DISPLAY 0.787234 (-6563 2012);
PAINT MONO (-6563 2012);
FORCEPROP 1 LASTPIN (-6375 2000) $PN 2
J 0
(-6413 2012);
DISPLAY 0.787234 (-6413 2012);
PAINT MONO (-6413 2012);
FORCEPROP 1 LAST MATERIAL CHIP
J 0
(-6575 2075);
DISPLAY 1.021277 (-6575 2075);
FORCEPROP 1 LAST WATTAGE 1/16W
J 2
(-6250 1950);
DISPLAY 0.808511 (-6250 1950);
FORCEPROP 1 LAST VALUE 0
J 2
(-6275 2000);
DISPLAY 1.021277 (-6275 2000);
FORCEPROP 1 LAST TOLERANCE 5%
J 0
(-6225 1950);
DISPLAY 1.021277 (-6225 1950);
FORCEPROP 1 LAST PACK_TYPE 0402LF
J 0
(-6775 1950);
DISPLAY 0.808511 (-6775 1950);
FORCEPROP 2 LAST CDS_LIB pure_quanta
J 0
(-6475 2000);
DISPLAY INVISIBLE (-6475 2000);
FORCEPROP 1 LAST PART_NUMBER CS00002JB13
J 0
(-6700 1900);
DISPLAY 0.808511 (-6700 1900);
DISPLAY INVISIBLE (-6700 1900);
FORCEPROP 1 LAST PATH I40
J 0
(-6525 2150);
DISPLAY 0.978723 (-6525 2150);
PAINT WHITE (-6525 2150);
DISPLAY INVISIBLE (-6525 2150);
FORCEADD Q_CAP..1
R 2
(-7175 1675);
FORCEPROP 1 LAST LOCATION C6085
J 2
(-7225 1775);
DISPLAY 0.808511 (-7225 1775);
FORCEPROP 0 LAST $SEC 1
J 0
(-7225 1825);
DISPLAY 0.680851 (-7225 1825);
PAINT MONO (-7225 1825);
DISPLAY INVISIBLE (-7225 1825);
FORCEPROP 0 LAST CDS_SEC 1
J 0
(-7225 1825);
DISPLAY 0.680851 (-7225 1825);
DISPLAY INVISIBLE (-7225 1825);
FORCEPROP 1 LASTPIN (-7175 1775) $PN 1
J 2
(-7185 1755);
DISPLAY 0.787234 (-7185 1755);
PAINT MONO (-7185 1755);
FORCEPROP 1 LASTPIN (-7175 1575) $PN 2
J 2
(-7185 1555);
DISPLAY 0.787234 (-7185 1555);
PAINT MONO (-7185 1555);
FORCEPROP 1 LAST TOLERANCE 10%
J 2
(-7225 1625);
DISPLAY 0.808511 (-7225 1625);
FORCEPROP 1 LAST PACK_TYPE 0402
J 2
(-7225 1475);
DISPLAY 0.808511 (-7225 1475);
FORCEPROP 1 LAST MATERIAL EMPTY
J 2
(-7225 1575);
DISPLAY 0.808511 (-7225 1575);
FORCEPROP 1 LAST VALUE 0.1UF
J 2
(-7225 1725);
DISPLAY 0.808511 (-7225 1725);
FORCEPROP 1 LAST VOLTAGE 25V
J 2
(-7225 1675);
DISPLAY 0.808511 (-7225 1675);
FORCEPROP 2 LAST CDS_LIB pure_quanta
J 0
(-7175 1675);
DISPLAY INVISIBLE (-7175 1675);
FORCEPROP 1 LAST PART_NUMBER CH4104K1B00
J 2
(-7225 1525);
DISPLAY 0.808511 (-7225 1525);
DISPLAY INVISIBLE (-7225 1525);
FORCEPROP 1 LAST PATH I41
J 2
(-7225 1825);
DISPLAY 0.978723 (-7225 1825);
PAINT WHITE (-7225 1825);
DISPLAY INVISIBLE (-7225 1825);
FORCEADD GND..1
(-7175 1250);
FORCEPROP 3 LASTPIN (-7175 1300) SIG_NAME GND\g
J 0
(-7165 1310);
DISPLAY 0.659574 (-7165 1310);
PAINT MONO (-7165 1310);
DISPLAY INVISIBLE (-7165 1310);
FORCEPROP 1 LAST SIZE 1B
J 0
(-7100 1200);
DISPLAY 0.872340 (-7100 1200);
PAINT AQUA (-7100 1200);
DISPLAY INVISIBLE (-7100 1200);
FORCEPROP 2 LAST CDS_LIB pure_quanta_power
J 0
(-7175 1250);
DISPLAY INVISIBLE (-7175 1250);
FORCEPROP 1 LAST HDL_POWER GND
J 0
(-7175 1400);
DISPLAY 0.872340 (-7175 1400);
PAINT GREEN (-7175 1400);
DISPLAY INVISIBLE (-7175 1400);
FORCEPROP 1 LAST PATH I42
J 0
(-7100 1250);
DISPLAY 0.872340 (-7100 1250);
PAINT AQUA (-7100 1250);
DISPLAY INVISIBLE (-7100 1250);
FORCEADD OFFPAGE..5
R 2
(-1800 2500);
FORCEPROP 2 LAST $XR1 255 
J 0
(-1521 2500);
DISPLAY 0.638298 (-1521 2500);
PAINT MONO (-1521 2500);
FORCEPROP 2 LAST $XR0 81 
J 0
(-1611 2500);
DISPLAY 0.638298 (-1611 2500);
PAINT MONO (-1611 2500);
FORCEPROP 2 LAST CDS_LIB standard
J 0
(-1800 2500);
DISPLAY INVISIBLE (-1800 2500);
FORCEPROP 1 LAST OFFPAGE TRUE
J 2
(-2125 2375);
DISPLAY 0.872340 (-2125 2375);
PAINT GREEN (-2125 2375);
DISPLAY INVISIBLE (-2125 2375);
FORCEPROP 1 LAST COMMENT_BODY TRUE
J 2
(-1900 2425);
DISPLAY 0.872340 (-1900 2425);
PAINT GREEN (-1900 2425);
DISPLAY INVISIBLE (-1900 2425);
FORCEPROP 2 LAST PATH I43
J 0
(-1625 2575);
DISPLAY 0.680851 (-1625 2575);
DISPLAY INVISIBLE (-1625 2575);
FORCEADD Q_RES..1
(-2875 2500);
FORCEPROP 1 LAST LOCATION R6241
J 0
(-3125 2500);
DISPLAY 0.872340 (-3125 2500);
FORCEPROP 0 LAST $SEC 1
J 0
(-2975 2625);
DISPLAY 0.680851 (-2975 2625);
PAINT MONO (-2975 2625);
DISPLAY INVISIBLE (-2975 2625);
FORCEPROP 0 LAST CDS_SEC 1
J 0
(-2975 2625);
DISPLAY 0.680851 (-2975 2625);
DISPLAY INVISIBLE (-2975 2625);
FORCEPROP 1 LASTPIN (-2975 2500) $PN 1
J 0
(-2963 2512);
DISPLAY 0.787234 (-2963 2512);
PAINT MONO (-2963 2512);
FORCEPROP 1 LASTPIN (-2775 2500) $PN 2
J 0
(-2813 2512);
DISPLAY 0.787234 (-2813 2512);
PAINT MONO (-2813 2512);
FORCEPROP 1 LAST TOLERANCE 5%
J 0
(-2625 2450);
DISPLAY 1.021277 (-2625 2450);
FORCEPROP 1 LAST PACK_TYPE 0402LF
J 0
(-3175 2450);
DISPLAY 0.808511 (-3175 2450);
FORCEPROP 1 LAST VALUE 0
J 2
(-2675 2500);
DISPLAY 1.021277 (-2675 2500);
FORCEPROP 1 LAST MATERIAL CHIP
J 0
(-2975 2575);
DISPLAY 1.021277 (-2975 2575);
FORCEPROP 1 LAST WATTAGE 1/16W
J 2
(-2650 2450);
DISPLAY 0.808511 (-2650 2450);
FORCEPROP 2 LAST CDS_LIB pure_quanta
J 0
(-2875 2500);
DISPLAY INVISIBLE (-2875 2500);
FORCEPROP 1 LAST PART_NUMBER CS00002JB13
J 0
(-3100 2400);
DISPLAY 0.808511 (-3100 2400);
DISPLAY INVISIBLE (-3100 2400);
FORCEPROP 1 LAST PATH I44
J 0
(-2925 2650);
DISPLAY 0.978723 (-2925 2650);
PAINT WHITE (-2925 2650);
DISPLAY INVISIBLE (-2925 2650);
FORCEADD Q_RES..1
(-3675 2300);
FORCEPROP 1 LAST LOCATION PR8004
J 0
(-3725 2350);
DISPLAY 0.978723 (-3725 2350);
FORCEPROP 2 LAST SEC 1
J 0
(-3725 2500);
DISPLAY 0.680851 (-3725 2500);
PAINT MONO (-3725 2500);
DISPLAY INVISIBLE (-3725 2500);
FORCEPROP 1 LASTPIN (-3775 2300) $PN 1
J 0
(-3763 2312);
DISPLAY 0.787234 (-3763 2312);
PAINT MONO (-3763 2312);
FORCEPROP 1 LASTPIN (-3575 2300) $PN 2
J 0
(-3613 2312);
DISPLAY 0.787234 (-3613 2312);
PAINT MONO (-3613 2312);
FORCEPROP 1 LAST VALUE 2.2
J 2
(-3750 2300);
DISPLAY 0.510638 (-3750 2300);
FORCEPROP 1 LAST PACK_TYPE 0402LF
J 0
(-3850 2250);
DISPLAY 0.510638 (-3850 2250);
FORCEPROP 1 LAST TOLERANCE 1%
J 0
(-3575 2250);
DISPLAY 0.510638 (-3575 2250);
FORCEPROP 1 LAST MATERIAL CHIP
J 0
(-3700 2250);
DISPLAY 0.510638 (-3700 2250);
FORCEPROP 2 LAST SEC_TYPE 0402LF
J 0
(-3725 2500);
DISPLAY 0.680851 (-3725 2500);
DISPLAY INVISIBLE (-3725 2500);
FORCEPROP 2 LAST CDS_LIB pure_quanta
J 0
(-3675 2300);
DISPLAY INVISIBLE (-3675 2300);
FORCEPROP 1 LAST WATTAGE 1/16W
J 2
(-3700 2150);
DISPLAY 0.978723 (-3700 2150);
DISPLAY INVISIBLE (-3700 2150);
FORCEPROP 1 LAST PART_NUMBER CS-2202FB01
J 0
(-3725 2400);
DISPLAY 0.638298 (-3725 2400);
DISPLAY INVISIBLE (-3725 2400);
FORCEPROP 1 LAST PATH I45
J 0
(-3725 2450);
DISPLAY 0.978723 (-3725 2450);
PAINT WHITE (-3725 2450);
DISPLAY INVISIBLE (-3725 2450);
FORCEADD GND..1
(-5800 1150);
FORCEPROP 3 LASTPIN (-5800 1200) SIG_NAME GND\g
J 0
(-5790 1210);
DISPLAY 0.659574 (-5790 1210);
PAINT MONO (-5790 1210);
DISPLAY INVISIBLE (-5790 1210);
FORCEPROP 1 LAST PATH I5
J 0
(-5850 1225);
DISPLAY 1.021277 (-5850 1225);
FORCEPROP 2 LAST CDS_LIB pure_quanta_power
J 0
(-5800 1150);
DISPLAY INVISIBLE (-5800 1150);
FORCEPROP 1 LAST SIZE 1B
J 0
(-5725 1100);
DISPLAY 0.872340 (-5725 1100);
PAINT AQUA (-5725 1100);
DISPLAY INVISIBLE (-5725 1100);
FORCEPROP 1 LAST HDL_POWER GND
J 0
(-5800 1300);
DISPLAY 0.872340 (-5800 1300);
PAINT GREEN (-5800 1300);
DISPLAY INVISIBLE (-5800 1300);
FORCEADD Q_RES..2
(-5600 950);
FORCEPROP 1 LAST LOCATION PR6004
J 0
(-5555 1075);
DISPLAY 0.617021 (-5555 1075);
PAINT AQUA (-5555 1075);
FORCEPROP 0 LAST $SEC 1
J 0
(-5550 1125);
DISPLAY 0.680851 (-5550 1125);
PAINT MONO (-5550 1125);
DISPLAY INVISIBLE (-5550 1125);
FORCEPROP 0 LAST CDS_SEC 1
J 0
(-5550 1125);
DISPLAY 0.680851 (-5550 1125);
DISPLAY INVISIBLE (-5550 1125);
FORCEPROP 1 LASTPIN (-5600 1050) $PN 1
J 0
(-5595 1012);
DISPLAY 0.787234 (-5595 1012);
PAINT MONO (-5595 1012);
FORCEPROP 1 LASTPIN (-5600 850) $PN 2
J 0
(-5595 860);
DISPLAY 0.787234 (-5595 860);
PAINT MONO (-5595 860);
FORCEPROP 1 LAST PACK_TYPE 0402LF
J 0
(-5560 775);
DISPLAY 0.617021 (-5560 775);
PAINT SKYBLUE (-5560 775);
FORCEPROP 1 LAST WATTAGE 1/16W
J 0
(-5560 925);
DISPLAY 0.617021 (-5560 925);
PAINT SKYBLUE (-5560 925);
FORCEPROP 1 LAST MATERIAL CHIP
J 0
(-5560 875);
DISPLAY 0.617021 (-5560 875);
PAINT SKYBLUE (-5560 875);
FORCEPROP 1 LAST TOLERANCE 1%
J 0
(-5555 975);
DISPLAY 0.617021 (-5555 975);
PAINT SKYBLUE (-5555 975);
FORCEPROP 1 LAST VALUE 11.5K
J 0
(-5555 1025);
DISPLAY 0.617021 (-5555 1025);
PAINT SKYBLUE (-5555 1025);
FORCEPROP 2 LAST CDS_LIB pure_quanta
J 0
(-5600 950);
DISPLAY INVISIBLE (-5600 950);
FORCEPROP 1 LAST PART_NUMBER CS31152FB03
J 0
(-5560 825);
DISPLAY 0.617021 (-5560 825);
PAINT BLUE (-5560 825);
DISPLAY INVISIBLE (-5560 825);
FORCEPROP 1 LAST PATH I6
J 0
(-5550 1125);
DISPLAY 0.978723 (-5550 1125);
PAINT WHITE (-5550 1125);
DISPLAY INVISIBLE (-5550 1125);
FORCEADD Q_CAP..1
(-5800 1350);
FORCEPROP 1 LAST LOCATION PC6009
J 0
(-5950 1400);
DISPLAY 0.617021 (-5950 1400);
PAINT AQUA (-5950 1400);
FORCEPROP 0 LAST $SEC 1
J 0
(-5950 1450);
DISPLAY 0.680851 (-5950 1450);
PAINT MONO (-5950 1450);
DISPLAY INVISIBLE (-5950 1450);
FORCEPROP 0 LAST CDS_SEC 1
J 0
(-5950 1450);
DISPLAY 0.680851 (-5950 1450);
DISPLAY INVISIBLE (-5950 1450);
FORCEPROP 1 LASTPIN (-5800 1450) $PN 1
J 0
(-5790 1430);
DISPLAY 0.787234 (-5790 1430);
PAINT MONO (-5790 1430);
FORCEPROP 1 LASTPIN (-5800 1250) $PN 2
J 0
(-5790 1230);
DISPLAY 0.787234 (-5790 1230);
PAINT MONO (-5790 1230);
FORCEPROP 1 LAST VALUE 1UF
J 0
(-5950 1325);
DISPLAY 0.617021 (-5950 1325);
PAINT SKYBLUE (-5950 1325);
FORCEPROP 1 LAST MATERIAL X6S
J 0
(-5950 1175);
DISPLAY 0.617021 (-5950 1175);
PAINT SKYBLUE (-5950 1175);
FORCEPROP 1 LAST VOLTAGE 25V
J 0
(-5950 1275);
DISPLAY 0.617021 (-5950 1275);
PAINT SKYBLUE (-5950 1275);
FORCEPROP 1 LAST PACK_TYPE C0402
J 0
(-5975 1075);
DISPLAY 0.617021 (-5975 1075);
PAINT SKYBLUE (-5975 1075);
FORCEPROP 1 LAST TOLERANCE 10%
J 0
(-5950 1225);
DISPLAY 0.617021 (-5950 1225);
PAINT SKYBLUE (-5950 1225);
FORCEPROP 2 LAST CDS_LIB pure_quanta
J 0
(-5800 1350);
DISPLAY INVISIBLE (-5800 1350);
FORCEPROP 1 LAST PART_NUMBER CH5104KEB02
J 0
(-6150 1125);
DISPLAY 0.617021 (-6150 1125);
PAINT BLUE (-6150 1125);
DISPLAY INVISIBLE (-6150 1125);
FORCEPROP 1 LAST PATH I7
J 0
(-5750 1500);
DISPLAY 0.978723 (-5750 1500);
PAINT WHITE (-5750 1500);
DISPLAY INVISIBLE (-5750 1500);
FORCEADD GND..1
(-6250 2150);
FORCEPROP 3 LASTPIN (-6250 2200) SIG_NAME GND\g
J 0
(-6240 2210);
DISPLAY 0.659574 (-6240 2210);
PAINT MONO (-6240 2210);
DISPLAY INVISIBLE (-6240 2210);
FORCEPROP 1 LAST PATH I8
J 0
(-6300 2225);
DISPLAY 1.021277 (-6300 2225);
FORCEPROP 2 LAST CDS_LIB pure_quanta_power
J 0
(-6250 2150);
DISPLAY INVISIBLE (-6250 2150);
FORCEPROP 1 LAST SIZE 1B
J 0
(-6175 2100);
DISPLAY 0.872340 (-6175 2100);
PAINT AQUA (-6175 2100);
DISPLAY INVISIBLE (-6175 2100);
FORCEPROP 1 LAST HDL_POWER GND
J 0
(-6250 2300);
DISPLAY 0.872340 (-6250 2300);
PAINT GREEN (-6250 2300);
DISPLAY INVISIBLE (-6250 2300);
FORCEADD QUANTA_TITLE_BLOCK_C..1
(675 -1275);
FORCEPROP 0 LAST CDS_CON_LAST_MODIFIED Thu Sep 14 16:12:47 2023
J 0
(-1210 -1260);
DISPLAY INVISIBLE (-1210 -1260);
FORCEPROP 1 LAST CUSTOM_TXT_CDS <CON_LAST_MODIFIED>
J 0
(-1210 -1260);
DISPLAY 0.978723 (-1210 -1260);
FORCEPROP 2 LAST CUSTOM_TXT_CDS <XR_PAGE_TITLE>
J 0
(-7215 3975);
DISPLAY 0.638298 (-7215 3975);
PAINT PINK (-7215 3975);
DISPLAY INVISIBLE (-7215 3975);
FORCEPROP 1 LAST CUSTOM_TXT_CDS <NAME_2>
J 0
(-2500 -1225);
FORCEPROP 1 LAST CUSTOM_TXT_CDS <NAME_1>
J 0
(-2500 -1100);
FORCEPROP 1 LAST CUSTOM_TXT_CDS <Q_NUMBER>
J 0
(-728 -1172);
DISPLAY 1.212766 (-728 -1172);
FORCEPROP 1 LAST CUSTOM_TXT_CDS <Q_PROJ>
J 0
(-1707 -1173);
DISPLAY 1.212766 (-1707 -1173);
FORCEPROP 1 LAST CUSTOM_TXT_CDS <Q_REV>
J 0
(491 -1172);
DISPLAY 1.212766 (491 -1172);
FORCEPROP 1 LAST CUSTOM_TXT_CDS <CON_PAGE_NUM> OF <CON_TOTAL_PAGES>
J 0
(229 -1257);
DISPLAY 0.978723 (229 -1257);
FORCEPROP 1 LAST Q_TITLE P1V2_AUX
J 0
(-8632 -1252);
DISPLAY 2.446809 (-8632 -1252);
PAINT GREEN (-8632 -1252);
FORCEPROP 2 LAST PAGE_BORDER TRUE
J 0
(-7215 3975);
DISPLAY 0.638298 (-7215 3975);
PAINT PINK (-7215 3975);
DISPLAY INVISIBLE (-7215 3975);
FORCEPROP 1 LAST CDS_LMAN_SYM_OUTLINE -9475,6775,100,-125
J 0
(675 -1275);
DISPLAY 0.468085 (675 -1275);
PAINT GREEN (675 -1275);
DISPLAY INVISIBLE (675 -1275);
FORCEPROP 2 LAST CDS_LIB pure_quanta
J 0
(675 -1275);
DISPLAY INVISIBLE (675 -1275);
FORCEPROP 2 LAST CDS_XR_PAGE_TITLE CR-271 : @T6G_MB_LIB.T6G(SCH_1):PAGE271
J 0
(-7215 3975);
DISPLAY 0.638298 (-7215 3975);
PAINT PINK (-7215 3975);
DISPLAY INVISIBLE (-7215 3975);
FORCEPROP 1 LAST COMMENT_BODY TRUE
J 0
(687 -1288);
DISPLAY 0.978723 (687 -1288);
PAINT GREEN (687 -1288);
DISPLAY INVISIBLE (687 -1288);
FORCEPROP 1 LAST Q_DEPT CCBU
J 1
(-3054 -1229);
DISPLAY 1.957447 (-3054 -1229);
PAINT GREEN (-3054 -1229);
DISPLAY INVISIBLE (-3054 -1229);
FORCEADD DNS..2
(-7250 1675);
PAINT RED (-7250 1675);
FORCEPROP 2 LAST CDS_LIB mstr_misc
J 0
(-7250 1675);
DISPLAY INVISIBLE (-7250 1675);
FORCEPROP 1 LAST COMMENT_BODY TRUE
R 1
J 0
(-7175 1450);
DISPLAY 0.872340 (-7175 1450);
PAINT GREEN (-7175 1450);
DISPLAY INVISIBLE (-7175 1450);
WIRE 16 -1 (-5600 850)(-5600 800);
WIRE 16 -1 (-3700 800)(-3700 925);
WIRE 16 -1 (-3100 700)(-3100 775);
WIRE 16 -1 (-4250 1400)(-3400 1400);
WIRE 16 -1 (-3400 1400)(-3400 1300);
WIRE 16 -1 (-3550 2900)(-3550 3050);
WIRE 16 -1 (-7700 2400)(-7700 2300);
WIRE 16 -1 (-7175 1575)(-7175 1300);
WIRE 16 -1 (-5800 1250)(-5800 1200);
WIRE 16 -1 (-8075 2000)(-7175 2000);
FORCEPROP 2 LAST SIG_NAME PWRGD_P1V8_AUX_R
J 0
(-7885 2010);
DISPLAY 0.680851 (-7885 2010);
WIRE 16 -1 (-7175 2000)(-6575 2000);
WIRE 16 -1 (-7175 2000)(-7175 1775);
WIRE 16 2175 (-8250 275)(-6550 275);
WIRE 16 2175 (-8250 275)(-8250 -175);
WIRE 16 2175 (-6550 275)(-6550 -175);
WIRE 16 2175 (-8250 -175)(-6550 -175);
WIRE 16 2175 (-8300 -850)(-6747 -850);
WIRE 16 2175 (-8300 -375)(-8300 -850);
WIRE 16 2175 (-6747 -375)(-6747 -850);
WIRE 16 2175 (-8300 -375)(-6747 -375);
WIRE 16 -1 (-4250 2500)(-3550 2500);
FORCEPROP 2 LAST SIG_NAME PWRGD_P1V2_AUX
J 0
(-4160 2510);
DISPLAY 0.617021 (-4160 2510);
FORCEPROP 2 LASTPROP $XRERR UNIQUE?
J 0
(-4400 2510);
DISPLAY 0.638298 (-4400 2510);
PAINT MONO (-4400 2510);
DISPLAY INVISIBLE (-4400 2510);
WIRE 16 -1 (-3550 2500)(-2975 2500);
WIRE 16 -1 (-3550 2500)(-3550 2700);
WIRE 16 -1 (-3575 2300)(-3200 2300);
FORCEPROP 2 LAST SIG_NAME SW_P1V2_AUX_BT_R
J 0
(-3485 2310);
DISPLAY 0.553191 (-3485 2310);
FORCEPROP 2 LASTPROP $XRERR UNIQUE?
J 0
(-3725 2310);
DISPLAY 0.638298 (-3725 2310);
PAINT MONO (-3725 2310);
DISPLAY INVISIBLE (-3725 2310);
WIRE 16 -1 (-3200 2300)(-3200 2275);
WIRE 16 -1 (-4250 2050)(-3200 2050);
FORCEPROP 2 LAST SIG_NAME SW_P1V2_AUX_PH
J 0
(-4160 1960);
DISPLAY 0.617021 (-4160 1960);
FORCEPROP 2 LASTPROP $XRERR UNIQUE?
J 0
(-4400 1960);
DISPLAY 0.638298 (-4400 1960);
PAINT MONO (-4400 1960);
DISPLAY INVISIBLE (-4400 1960);
WIRE 16 -1 (-3200 2050)(-3200 2075);
WIRE 16 -1 (-3200 2000)(-3200 2050);
WIRE 16 -1 (-3200 2000)(-2825 2000);
WIRE 16 -1 (-4250 2000)(-3200 2000);
WIRE 16 -1 (-4250 2300)(-3775 2300);
FORCEPROP 2 LAST SIG_NAME SW_P1V2_AUX_BT
J 0
(-4160 2310);
DISPLAY 0.489362 (-4160 2310);
FORCEPROP 2 LASTPROP $XRERR UNIQUE?
J 0
(-4400 2310);
DISPLAY 0.638298 (-4400 2310);
PAINT MONO (-4400 2310);
DISPLAY INVISIBLE (-4400 2310);
WIRE 16 -1 (-7700 2700)(-7300 2700);
WIRE 16 -1 (-7700 2700)(-7700 2600);
WIRE 16 -1 (-7700 2800)(-7700 2700);
WIRE 16 -1 (-4250 1200)(-4100 1200);
WIRE 16 -1 (-4100 1200)(-4100 1150);
WIRE 16 -1 (-4250 1150)(-4100 1150);
WIRE 16 -1 (-4100 1150)(-4100 800);
WIRE 16 -1 (-2550 1700)(-2550 1600);
WIRE 16 -1 (-2550 1600)(-2150 1600);
WIRE 16 -1 (-2150 1600)(-1725 1600);
WIRE 16 -1 (-2150 1700)(-2150 1600);
WIRE 16 -1 (-1725 1600)(-1500 1600);
WIRE 16 -1 (-1725 1700)(-1725 1600);
WIRE 16 -1 (-1500 1600)(-1300 1600);
WIRE 16 -1 (-1500 1500)(-1500 1600);
WIRE 16 -1 (-1300 1600)(-800 1600);
WIRE 16 -1 (-1300 1700)(-1300 1600);
WIRE 16 -1 (-800 1600)(-800 1700);
WIRE 16 -1 (-1950 800)(-1400 800);
WIRE 16 -1 (-1400 800)(-1400 1225);
WIRE 16 -1 (-1400 1225)(-250 1225);
WIRE 16 -1 (-1950 1225)(-1400 1225);
WIRE 16 -1 (-250 1225)(-250 2000);
WIRE 16 -1 (-250 2000)(-800 2000);
WIRE 16 -1 (-800 1900)(-800 2000);
WIRE 16 -1 (-800 2000)(-1300 2000);
WIRE 16 -1 (-1300 2100)(-1300 2000);
WIRE 16 -1 (-1300 1900)(-1300 2000);
WIRE 16 -1 (-1300 2000)(-1725 2000);
WIRE 16 -1 (-1725 1900)(-1725 2000);
WIRE 16 -1 (-2150 2000)(-1725 2000);
WIRE 16 -1 (-2150 1900)(-2150 2000);
WIRE 16 -1 (-2550 2000)(-2150 2000);
WIRE 16 -1 (-2550 1900)(-2550 2000);
WIRE 16 -1 (-2625 2000)(-2550 2000);
WIRE 16 -1 (-6775 1550)(-6500 1550);
WIRE 16 -1 (-6775 1650)(-6775 1550);
WIRE 16 -1 (-5975 1800)(-6300 1800);
WIRE 16 -1 (-6300 1700)(-6300 1800);
WIRE 16 -1 (-6900 2400)(-6900 2275);
WIRE 16 -1 (-6900 2275)(-6300 2275);
WIRE 16 -1 (-6300 2400)(-6300 2275);
WIRE 16 -1 (-6300 2275)(-6250 2275);
WIRE 16 -1 (-5700 2275)(-6250 2275);
WIRE 16 -1 (-6250 2275)(-6250 2200);
WIRE 16 -1 (-5700 2400)(-5700 2275);
WIRE 16 -1 (-2775 2500)(-1850 2500);
FORCEPROP 2 LAST SIG_NAME PWRGD_P1V2_AUX_R
J 0
(-2435 2510);
DISPLAY 0.617021 (-2435 2510);
WIRE 16 -1 (-4250 1550)(-3300 1550);
FORCEPROP 2 LAST SIG_NAME P1V2_AUX_FB
J 0
(-4160 1560);
DISPLAY 0.617021 (-4160 1560);
FORCEPROP 2 LASTPROP $XRERR UNIQUE?
J 0
(-4400 1560);
DISPLAY 0.638298 (-4400 1560);
PAINT MONO (-4400 1560);
DISPLAY INVISIBLE (-4400 1560);
WIRE 16 -1 (-3300 1550)(-3300 1225);
WIRE 16 -1 (-3300 1225)(-3100 1225);
WIRE 16 -1 (-2600 1225)(-3100 1225);
WIRE 16 -1 (-3100 975)(-3100 1225);
WIRE 16 -1 (-2600 1225)(-2150 1225);
WIRE 16 -1 (-2600 1225)(-2600 800);
WIRE 16 -1 (-2600 800)(-2150 800);
WIRE 16 -1 (-5775 1800)(-5050 1800);
FORCEPROP 2 LAST SIG_NAME P1V2_AUX_MODE
J 0
(-5635 1810);
DISPLAY 0.617021 (-5635 1810);
FORCEPROP 2 LASTPROP $XRERR UNIQUE?
J 0
(-5875 1810);
DISPLAY 0.638298 (-5875 1810);
PAINT MONO (-5875 1810);
DISPLAY INVISIBLE (-5875 1810);
WIRE 16 -1 (-6375 2000)(-5050 2000);
FORCEPROP 2 LAST SIG_NAME P1V2_AUX_ENABLE
J 0
(-6135 2010);
DISPLAY 0.617021 (-6135 2010);
FORCEPROP 2 LASTPROP $XRERR UNIQUE?
J 0
(-6375 2010);
DISPLAY 0.638298 (-6375 2010);
PAINT MONO (-6375 2010);
DISPLAY INVISIBLE (-6375 2010);
WIRE 16 -1 (-6300 1550)(-5800 1550);
WIRE 16 -1 (-5800 1550)(-5050 1550);
FORCEPROP 2 LAST SIG_NAME P1V2_AUX_VCC
J 0
(-5635 1560);
DISPLAY 0.617021 (-5635 1560);
FORCEPROP 2 LASTPROP $XRERR UNIQUE?
J 0
(-5875 1560);
DISPLAY 0.638298 (-5875 1560);
PAINT MONO (-5875 1560);
DISPLAY INVISIBLE (-5875 1560);
WIRE 16 -1 (-5800 1450)(-5800 1550);
WIRE 16 -1 (-5400 2500)(-5050 2500);
WIRE 16 -1 (-5400 2700)(-5400 2500);
WIRE 16 -1 (-5700 2700)(-5400 2700);
WIRE 16 -1 (-5700 2700)(-5700 2600);
WIRE 16 -1 (-5700 2700)(-6300 2700);
FORCEPROP 2 LAST SIG_NAME SW_P12V_AUX_P1V2_AUX_FLT
J 0
(-6535 2735);
DISPLAY 0.617021 (-6535 2735);
FORCEPROP 2 LASTPROP $XRERR UNIQUE?
J 0
(-6775 2735);
DISPLAY 0.638298 (-6775 2735);
PAINT MONO (-6775 2735);
DISPLAY INVISIBLE (-6775 2735);
WIRE 16 -1 (-6300 2600)(-6300 2700);
WIRE 16 -1 (-6900 2700)(-6300 2700);
WIRE 16 -1 (-6900 2600)(-6900 2700);
WIRE 16 -1 (-7100 2700)(-6900 2700);
WIRE 16 2175 (-8450 4100)(-6340 4100);
WIRE 16 2175 (-8450 5050)(-8450 4100);
WIRE 16 2175 (-6340 5050)(-6340 4100);
WIRE 16 2175 (-8450 5050)(-6340 5050);
WIRE 16 -1 (-5600 1050)(-5600 1200);
WIRE 16 -1 (-5600 1200)(-5050 1200);
FORCEPROP 2 LAST SIG_NAME P1V2_AUX_CS
J 0
(-5585 1210);
DISPLAY 0.617021 (-5585 1210);
FORCEPROP 2 LASTPROP $XRERR UNIQUE?
J 0
(-5825 1210);
DISPLAY 0.638298 (-5825 1210);
PAINT MONO (-5825 1210);
DISPLAY INVISIBLE (-5825 1210);
WIRE 16 -1 (-4250 1300)(-3700 1300);
FORCEPROP 2 LAST SIG_NAME P1V2_AUX_REF
J 0
(-4160 1310);
DISPLAY 0.617021 (-4160 1310);
FORCEPROP 2 LASTPROP $XRERR UNIQUE?
J 0
(-4400 1310);
DISPLAY 0.638298 (-4400 1310);
PAINT MONO (-4400 1310);
DISPLAY INVISIBLE (-4400 1310);
WIRE 16 -1 (-3700 1300)(-3700 1125);
DOT 1 (-3550 2500);
DOT 1 (-7175 2000);
DOT 1 (-1500 1600);
DOT 1 (-3100 1225);
DOT 1 (-6300 2700);
DOT 1 (-1300 1600);
DOT 1 (-5700 2700);
DOT 1 (-7700 2700);
DOT 1 (-1300 2000);
DOT 1 (-800 2000);
DOT 1 (-1400 1225);
DOT 1 (-2600 1225);
DOT 1 (-6250 2275);
DOT 1 (-6300 2275);
DOT 1 (-5800 1550);
DOT 1 (-4100 1150);
DOT 1 (-6900 2700);
DOT 1 (-1725 2000);
DOT 1 (-1725 1600);
DOT 1 (-2150 2000);
DOT 1 (-2150 1600);
DOT 1 (-2550 2000);
DOT 1 (-3200 2050);
DOT 1 (-3200 2000);
FORCENOTE
RCS=11.5K OCP=3A
(-5500 650) 0;
DISPLAY LEFT (-5500 650);
DISPLAY 0.808511 (-5500 650);
FORCENOTE
3RD 
(-8275 -700) 0;
DISPLAY LEFT (-8275 -700);
DISPLAY 1.170213 (-8275 -700);
PAINT WHITE (-8275 -700);
FORCENOTE
R1
(-2050 1400) 0;
DISPLAY LEFT (-2050 1400);
DISPLAY 1.021277 (-2050 1400);
FORCENOTE
2ND 
(-8275 -625) 0;
DISPLAY LEFT (-8275 -625);
DISPLAY 1.170213 (-8275 -625);
PAINT WHITE (-8275 -625);
FORCENOTE
1ST 
(-8275 -550) 0;
DISPLAY LEFT (-8275 -550);
DISPLAY 1.170213 (-8275 -550);
PAINT WHITE (-8275 -550);
FORCENOTE
IC TABLE
(-8225 175) 0;
DISPLAY LEFT (-8225 175);
DISPLAY 1.170213 (-8225 175);
PAINT WHITE (-8225 175);
FORCENOTE
MAX CURRENT=2.1A
(-8400 4515) 0;
DISPLAY LEFT (-8400 4515);
DISPLAY 1.170213 (-8400 4515);
PAINT WHITE (-8400 4515);
FORCENOTE
OVER CURRENT PROTECTION(IMAX*1.3)=3A
(-8400 4425) 0;
DISPLAY LEFT (-8400 4425);
DISPLAY 1.170213 (-8400 4425);
PAINT WHITE (-8400 4425);
FORCENOTE
SLEW RATE=2.5A/US
(-8400 4350) 0;
DISPLAY LEFT (-8400 4350);
DISPLAY 1.170213 (-8400 4350);
PAINT WHITE (-8400 4350);
FORCENOTE
WORK FREQUENCY=600KHZ
(-8400 4250) 0;
DISPLAY LEFT (-8400 4250);
DISPLAY 1.276596 (-8400 4250);
PAINT WHITE (-8400 4250);
FORCENOTE
EFFICENCY>90%@TDC
(-8400 4150) 0;
DISPLAY LEFT (-8400 4150);
DISPLAY 1.170213 (-8400 4150);
PAINT WHITE (-8400 4150);
FORCENOTE
TRANSIENT TOLERANCE<100MV
(-8400 4671) 0;
DISPLAY LEFT (-8400 4671);
DISPLAY 1.170213 (-8400 4671);
PAINT WHITE (-8400 4671);
FORCENOTE
OUTPUT VOLTAGE=1.2V +/-5%
(-8400 4825) 0;
DISPLAY LEFT (-8400 4825);
DISPLAY 1.170213 (-8400 4825);
PAINT WHITE (-8400 4825);
FORCENOTE
DESIGN SPECIFICATION
(-8400 4929) 0;
DISPLAY LEFT (-8400 4929);
DISPLAY 1.829787 (-8400 4929);
PAINT WHITE (-8400 4929);
FORCENOTE
TDC=1.6A
(-8400 4590) 0;
DISPLAY LEFT (-8400 4590);
DISPLAY 1.170213 (-8400 4590);
PAINT WHITE (-8400 4590);
FORCENOTE
OUTPUT RIPPLE<30MV
(-8400 4754) 0;
DISPLAY LEFT (-8400 4754);
DISPLAY 1.170213 (-8400 4754);
PAINT WHITE (-8400 4754);
FORCENOTE
FCCM/FREQ.=600KHZ
(-7000 1825) 0;
DISPLAY LEFT (-7000 1825);
DISPLAY 0.808511 (-7000 1825);
FORCENOTE
ENABLE: VIH>1.27V
(-5875 2075) 0;
DISPLAY LEFT (-5875 2075);
DISPLAY 0.808511 (-5875 2075);
FORCENOTE
VOUT=0.6(1+R1/R2)=1.2V
(-3275 250) 0;
DISPLAY LEFT (-3275 250);
DISPLAY 1.595745 (-3275 250);
FORCENOTE
R2
(-2875 1000) 0;
DISPLAY LEFT (-2875 1000);
DISPLAY 1.021277 (-2875 1000);
FORCENOTE
DCR=20 MOHM
(-3200 1675) 0;
DISPLAY LEFT (-3200 1675);
DISPLAY 0.808511 (-3200 1675);
FORCENOTE
PCMC063T-2R2MN
(-3200 1825) 0;
DISPLAY LEFT (-3200 1825);
DISPLAY 0.808511 (-3200 1825);
FORCENOTE
ISAT=13.5A @100C
(-3200 1750) 0;
DISPLAY LEFT (-3200 1750);
DISPLAY 0.808511 (-3200 1750);
FORCENOTE
7.3*6.6*3
(-3200 1900) 0;
DISPLAY LEFT (-3200 1900);
DISPLAY 0.808511 (-3200 1900);
FORCENOTE
R&C TABLE
(-8275 -475) 0;
DISPLAY LEFT (-8275 -475);
DISPLAY 1.170213 (-8275 -475);
PAINT WHITE (-8275 -475);
FORCENOTE
1ST AL008626000/MPQ8626GD-Z/MPS
(-8225 100) 0;
DISPLAY LEFT (-8225 100);
DISPLAY 1.021277 (-8225 100);
PAINT WHITE (-8225 100);
FORCENOTE
2ND AL053317005/RS53317LR/REEDSEMI
(-8225 25) 0;
DISPLAY LEFT (-8225 25);
DISPLAY 1.021277 (-8225 25);
PAINT WHITE (-8225 25);
FORCENOTE
3RD AL54J061000/TPS54J061RPGR/TI
(-8225 -50) 0;
DISPLAY LEFT (-8225 -50);
DISPLAY 1.021277 (-8225 -50);
PAINT WHITE (-8225 -50);
QUIT
